# ZAIUS-MB-EVT3-HW-EBOM-X00_20161228-add_2nd_source_X15-20170106-Final.xls — Changelist (bom)
| BOM Change List Date:Mon Jan 02 09:33:38 GMT+08:00 2017 |  |  |  |  |  |  |  |  |  |
| New BOM file : ZAIUS-MB-EVT3-HW-EBOM-X00_20161228-add 2nd source_X14-20170102.xls |  |  |  |  |  |  |  |  |  |
| Old BOM file : ZAIUS-MB-EVT2-HW-EBOM-X01_20161123_1200-add 2nd source_X13-20161212-Final-b.xls |  |  |  |  |  |  |  |  |  |
| ##### Add Parts |  |  |  |  |  |  |  |  |  |
| Item | Location | Qty | Foxconn P/N | Part Description | Manufacturer Full Name | Manufacturer P/N | RoHS | Sheet |  |
| 1 | C84,C98,C793,C2186 | 4 | 620103700-015-G | CAP,100nF,+/-10%,X7R,10V,G,SMD0402 | MURATA ELEC. NORTH AMERICA | GRM155R71A104K |  | PWA BOM |  |
|  |  |  | 620103700-023-G | CAP,100nF,+/-10%,X7R,10V,G,SMD0402 | TAIYO ELECTRIC IND.CO.LTD | LMK105B7104KV-F |  | PWA BOM |  |
|  |  |  | 620103700-026-G | CAP,100nF,+/-10%,X7R,10V,G,SMD0402 | SAMSUNG SEMICONDUCTOR | CL05B104KP5NNNC |  | PWA BOM |  |
| 2 | C62,C777 | 2 | 62012WD00-015-G | CAP,4.7uF,+/-20%,X6S,6.3V,G,SMD0402 | MURATA ELEC. NORTH AMERICA | GRM155C80J475MEAAD |  | PWA BOM |  |
|  |  |  | 62012WD00-023-G | CAP,4.7uF,+/-20%,X6S,6.3V,G,SMD0402 | TAIYO ELECTRIC IND.CO.LTD | JMK105BC6475MV-F |  | PWA BOM |  |
| 3 | C776,C799 | 2 | 62012NU00-015-G | CAP,1uF,+/-10%,X7R,6.3V,G,SMD0402 | MURATA ELEC. NORTH AMERICA | GRM155R70J105KA12D |  | PWA BOM |  |
|  |  |  | 62012NU00-026-G | CAP,1uF,+/-10%,X7R,6.3V,G,SMD0402 | SAMSUNG SEMICONDUCTOR | CL05B105KQ5NQNC |  | PWA BOM |  |
| 4 | C79,C813 | 2 | 62012P100-015-G | CAP,2.2uF,+/-20%,X7S,10V,G,SMD0402 | MURATA ELEC. NORTH AMERICA | GRM155C71A225M |  | PWA BOM |  |
| 5 | C66,C75,C76,C77,C81,C82,C97,C796,C797,C798,C800 | 11 | 62011DF01-015-G | CAP,220nF,+/-10%,X7R,16V,G,SMD0402 | MURATA ELEC. NORTH AMERICA | GRM155R71C224K |  | PWA BOM |  |
|  |  |  | 62011DF00-026-G | CAP,220nF,+/-10%,X7R,16V,G,SMD0402 | SAMSUNG SEMICONDUCTOR | CL05B224KO5NNNC |  | PWA BOM |  |
|  |  |  | 62011DF00-023-G | CAP,220nF,+/-10%,X7R,16V,G,SMD0402 | TAIYO ELECTRIC IND.CO.LTD | EMK105B7224KV-FR |  | PWA BOM |  |
| 6 | C78,C95,C96,C791,C792,C811 | 6 | 62011SJ00-026-G | CAP,470nF,+/-10%,X7R,6.3V,G,SMD0402 | SAMSUNG SEMICONDUCTOR | CL05B474KQ5NNNC |  | PWA BOM |  |
|  |  |  | 62011SJ00-023-G | CAP,470nF,+/-10%,X7R,6.3V,G,SMD0402 | TAIYO ELECTRIC IND.CO.LTD | JMK105B7474KV-F |  | PWA BOM |  |
| 7 | C812 | 1 | 62012H100-015-G | CAP,10uF,+/-20%,X6S,10V,G,SMD0603 | MURATA ELEC. NORTH AMERICA | GRM188C81A106M |  | PWA BOM |  |
|  |  |  | 62012H100-026-G | CAP,10uF,+/-20%,X6S,10V,G,SMD0603 | SAMSUNG SEMICONDUCTOR | CL10X106MP8NRNC |  | PWA BOM |  |
|  |  |  | 62012H100-023-G | CAP,10uF,+/-20%,X6S,10V,G,SMD0603 | TAIYO ELECTRIC IND.CO.LTD | LMK107BC6106MA-T |  | PWA BOM |  |
| 8 | C2182,C2183,C2184,C2185 | 4 | 620108B00-015-G | CAP,120pF,+/-5%,NPO(C0G),50V,G,SMD0402 | MURATA ELEC. NORTH AMERICA | GRM1555C1H121J |  | PWA BOM |  |
| 9 | PUAR15,PSAR15,PRAR15,PQAR15,PPAR15,PIAR15,PFAR15,PEAR15,R1840,R1841,R1842 | 11 | 610107A00-017-G | RES,0 Ohm,+/-5%,1/16W,G,SMD0402 | KOA SPEER ELECTRONICS, INC. | RK73Z1ETTP |  | PWA BOM |  |
|  |  |  | 610107A00-024-G | RES,0 Ohm,+/-5%,1/16W,G,SMD0402 | PANASONIC INDUSTRIAL CO.,LTD. | ERJ2GE0R00X |  | PWA BOM |  |
|  |  |  | 610107A00-029-G | RES,0 Ohm,+/-5%,1/16W,G,SMD0402 | VISHAY ENTER TECHNO LOGY.INC | CRCW04020000Z0ED |  | PWA BOM |  |
| 10 | PHAR39,R906,R914 | 3 | 61010G500-017-G | RES,10KOhm,+/-1%,1/16W,G,SMD0402 | KOA SPEER ELECTRONICS, INC. | RK73H1ETTP1002F |  | PWA BOM |  |
|  |  |  | 61010G500-029-G | RES,10KOhm,+/-1%,1/16W,G,SMD0402 | VISHAY ENTER TECHNO LOGY.INC | CRCW040210K0FKED |  | PWA BOM |  |
|  |  |  | 61010G500-024-G | RES,10KOhm,+/-1%,1/16W,G,SMD0402 | PANASONIC INDUSTRIAL CO.,LTD. | ERJ2RKF1002X |  | PWA BOM |  |
| 11 | PBNR24,PANR24 | 2 | 61011CS00-017-G | RES,750KOhm,+/-1%,1/16W,G,SMD0402 | KOA SPEER ELECTRONICS, INC. | RK73H1ETTP7503F |  | PWA BOM |  |
| 12 | PHAQ6 | 1 | 51032D100-237-G | MOS N,DMN10H220L-7,100V,1.6A,220m@10V,G,SOT-23-3,SMD | DIODES INCORPORATION | DMN10H220L-7 |  | PWA BOM |  |
| 13 | R1836,R1837,R1838,R1839 | 4 | 610124C00-017-G | RES,57.6 Ohm,+/-1%,1/16W,G,SMD0402 | KOA SPEER ELECTRONICS, INC. | RK73H1ETTP57R6F |  | PWA BOM |  |
|  |  |  | 610124C00-024-G | RES,57.6 Ohm,+/-1%,1/16W,G,SMD0402 | PANASONIC | ERJ2RKF57R6X |  | PWA BOM |  |
| 14 | Q93 | 1 | 51030QP00-237-G | MOS N,BSS138W-7-F,50V,0.2A,3.5ohm@10V,G,SOT323-3,SMD | DIODES INCORPORATION | BSS138W-7-F |  | PWA BOM |  |
| 15 | U180 | 1 | 310109D00-031-G | IC,Gate&Inverter,74LVC1G32GW,1.65~5.5V,G,TSSOP-5,SMD | NXP SEMICONDUCTORS | 74LVC1G32GW |  | PWA BOM |  |
| ##### Remove Parts |  |  |  |  |  |  |  |  |  |
| Item | Location | Qty | Foxconn P/N | Part Description | Manufacturer Full Name | Manufacturer P/N | RoHS | Sheet |  |
| 1 | C204,C205 | 2 | 620103700-015-G | CAP,100nF,+/-10%,X7R,10V,G,SMD0402 | MURATA ELEC. NORTH AMERICA | GRM155R71A104K |  | PWA BOM |  |
|  |  |  | 620103700-023-G | CAP,100nF,+/-10%,X7R,10V,G,SMD0402 | TAIYO ELECTRIC IND.CO.LTD | LMK105B7104KV-F |  | PWA BOM |  |
|  |  |  | 620103700-026-G | CAP,100nF,+/-10%,X7R,10V,G,SMD0402 | SAMSUNG SEMICONDUCTOR | CL05B104KP5NNNC |  | PWA BOM |  |
| 2 | C757 | 1 | 62012P100-015-G | CAP,2.2uF,+/-20%,X7S,10V,G,SMD0402 | MURATA ELEC. NORTH AMERICA | GRM155C71A225M |  | PWA BOM |  |
| 3 | C202 | 1 | 62012NU00-015-G | CAP,1uF,+/-10%,X7R,6.3V,G,SMD0402 | MURATA ELEC. NORTH AMERICA | GRM155R70J105KA12D |  | PWA BOM |  |
|  |  |  | 62012NU00-026-G | CAP,1uF,+/-10%,X7R,6.3V,G,SMD0402 | SAMSUNG SEMICONDUCTOR | CL05B105KQ5NQNC |  | PWA BOM |  |
| 4 | C138,C897,C904 | 3 | 62011DF01-015-G | CAP,220nF,+/-10%,X7R,16V,G,SMD0402 | MURATA ELEC. NORTH AMERICA | GRM155R71C224K |  | PWA BOM |  |
|  |  |  | 62011DF00-026-G | CAP,220nF,+/-10%,X7R,16V,G,SMD0402 | SAMSUNG SEMICONDUCTOR | CL05B224KO5NNNC |  | PWA BOM |  |
|  |  |  | 62011DF00-023-G | CAP,220nF,+/-10%,X7R,16V,G,SMD0402 | TAIYO ELECTRIC IND.CO.LTD | EMK105B7224KV-FR |  | PWA BOM |  |
| 5 | C184,C231,C232 | 3 | 620107G00-015-G | CAP,47nF,+/-10%,X7R,16V,G,SMD0402 | MURATA ELEC. NORTH AMERICA | GRM155R71C473K |  | PWA BOM |  |
|  |  |  | 620107G00-023-G | CAP,47nF,+/-10%,X7R,16V,G,SMD0402 | TAIYO ELECTRIC IND.CO.LTD | EMK105B7473KV-F |  | PWA BOM |  |
|  |  |  | 620107G00-026-G | CAP,47nF,+/-10%,X7R,16V,G,SMD0402 | SAMSUNG SEMICONDUCTOR | CL05B473KO5NNNC |  | PWA BOM |  |
| 6 | C264,C2171 | 2 | 62012PS00-015-G | CAP,10uF,+/-20%,X6S,4V,G,SMD0402 | MURATA ELEC. NORTH AMERICA | GRM155C80G106M |  | PWA BOM |  |
|  |  |  | 62012PS00-023-G | CAP,10uF,+/-20%,X6S,4V,G,SMD0402 | TAIYO ELECTRIC IND.CO.LTD | AMK105CC6106MV-F |  | PWA BOM |  |
| 7 | R905,R915 | 2 | 61010G500-017-G | RES,10KOhm,+/-1%,1/16W,G,SMD0402 | KOA SPEER ELECTRONICS, INC. | RK73H1ETTP1002F |  | PWA BOM |  |
|  |  |  | 61010G500-029-G | RES,10KOhm,+/-1%,1/16W,G,SMD0402 | VISHAY ENTER TECHNO LOGY.INC | CRCW040210K0FKED |  | PWA BOM |  |
|  |  |  | 61010G500-024-G | RES,10KOhm,+/-1%,1/16W,G,SMD0402 | PANASONIC INDUSTRIAL CO.,LTD. | ERJ2RKF1002X |  | PWA BOM |  |
| 8 | PBFR517,PBER517,PAFR517,PAER518,PBMR602,PBAR602,PAMR602,PAAR602 | 8 | 61010L100-017-G | RES,100KOhm,+/-1%,1/16W,G,SMD0402 | KOA SPEER ELECTRONICS, INC. | RK73H1ETTP1003F |  | PWA BOM |  |
|  |  |  | 61010L106-029-G | RES,100KOhm,+/-1%,1/16W,G,SMD0402 | VISHAY ENTER TECHNO LOGY.INC | CRCW0402100KFKEDC |  | PWA BOM |  |
|  |  |  | 61010L100-024-G | RES,100KOhm,+/-1%,1/16W,G,SMD0402 | PANASONIC INDUSTRIAL CO.,LTD. | ERJ2RKF1003X |  | PWA BOM |  |
| 9 | QN3 | 1 | 510503B00-223-G | MOS N/N,NTZD3154NT1G,20V,0.54A,550m24.5V,G,SOT563-6,SMD | ON SEMICONDUCTOR CORP | NTZD3154NT1G |  | PWA BOM |  |
| 10 | R1802 | 1 | 610100T00-017-G | RES,1KOhm,+/-5%,1/16W,G,SMD0402 | KOA SPEER ELECTRONICS, INC. | RK73B1ETTP102J |  | PWA BOM |  |
|  |  |  | 610100T00-024-G | RES,1KOhm,+/-5%,1/16W,G,SMD0402 | PANASONIC INDUSTRIAL CO.,LTD. | ERJ2GEJ102X |  | PWA BOM |  |
| 11 | R1266,R1270,R1274,R1278 | 4 | 61011CY00-017-G | RES,5.6KOhm,+/-1%,1/16W,G,SMD0402 | KOA SPEER ELECTRONICS, INC. | RK73H1ETTP5601F |  | PWA BOM |  |
|  |  |  | 61011CY00-029-G | RES,5.6KOhm,+/-1%,1/16W,G,SMD0402 | VISHAY ENTER TECHNO LOGY.INC | CRCW04025K60FKED |  | PWA BOM |  |
| 12 | J104,J117,J125 | 3 | ASP-195607-01 | CONN,Pin Header,1X2,V/T,Bla,2.54mm,10u,G,SMD-2 | SAMTEC INC. | ASP-195607-01 |  | PWA BOM |  |
| ##### Change Parts |  |  |  |  |  |  |  |  |  |
| Item | Location | Qty | Foxconn P/N | Part Description | Manufacturer Full Name | Manufacturer P/N | RoHS | Sheet | Remark |
| 1 | C1458,C1463,C1486,C1489,C1492,C1774,C1775,C1793,C1795,C1839,C1840,C1883,C1885,C1938,C1939,C1950,C1976 | 17 | 620115801-015-G | CAP,22uF,+/-10%,X7R,10V,G,SMD1206 | MURATA ELEC. NORTH AMERICA | GRM31CR71A226KE15L |  | PWA BOM | In New BOM |
|  |  |  | 620115800-023-G | CAP,22uF,+/-10%,X7R,10V,G,SMD1206 | TAIYO ELECTRIC IND.CO.LTD | LMK316B7226KL-TR |  | PWA BOM | In New BOM |
|  |  |  | 620115800-026-G | CAP,22uF,+/-10%,X7R,10V,G,SMD1206 | SAMSUNG | CL31B226KPHNNNE |  | PWA BOM | In New BOM |
|  | C1458,C1463,C1486,C1489,C1492,C1774,C1775,C1793,C1795,C1839,C1840,C1883,C1885,C1938,C1939,C1950,C1976 | 17 | 620115801-015-G | CAP,22uF,+/-10%,X7R,10V,G,SMD1206 | MURATA ELEC. NORTH AMERICA | GRM31CR71A226KE15L |  | PWA BOM | In Old BOM |
|  |  |  | 620115800-023-G | CAP,22uF,+/-10%,X7R,10V,G,SMD1206 | TAIYO ELECTRIC IND.CO.LTD | LMK316B7226KL-TR |  | PWA BOM | In Old BOM |
| 2 | C1542 | 1 | 62010GW00-015-G | CAP,10pF,+/-5%,NPO,50V,G,SMD0402 | MURATA ELEC. NORTH AMERICA | GRM1555C1H100J |  | PWA BOM | In New BOM |
|  |  |  | 620102D00-026-G | CAP,10pF,+/-5%,NPO,50V,G,SMD0402 | SAMSUNG | CL05C100JB5NNNC |  | PWA BOM | In New BOM |
|  | C1542 | 1 | 62010GW00-015-G | CAP,10pF,+/-5%,NPO,50V,G,SMD0402 | MURATA ELEC. NORTH AMERICA | GRM1555C1H100J |  | PWA BOM | In Old BOM |
| 3 | PBNC1,PANC8,PQPC16,C2013,C2015,C2017,C2019,PSRC3008 | 8 | 620130V00-015-G | CAP,10uF,+/-20%,X6S,16V,G,SMD0603 | MURATA ELEC. NORTH AMERICA | GRM188C81C106MA73D |  | PWA BOM | In New BOM |
|  |  |  | 620130V00-023-G | CAP,10uF,+/-20%,X6S,16V,G,SMD0603 | TAIYO ELECTRIC IND.CO.LTD | EMK107BC6106MA-T |  | PWA BOM | In New BOM |
|  |  |  | 620130V00-026-G | CAP,10uF,+/-20%,X6S,16V,G,SMD0603 | SAMSUNG | CL10X106MO8NRNC |  | PWA BOM | In New BOM |
|  | PBNC1,PANC8,PQPC16,C2013,C2015,C2017,C2019,PSRC3008 | 8 | 620130V00-015-G | CAP,10uF,+/-20%,X6S,16V,G,SMD0603 | MURATA ELEC. NORTH AMERICA | GRM188C81C106MA73D |  | PWA BOM | In Old BOM |
|  |  |  | 620130V00-023-G | CAP,10uF,+/-20%,X6S,16V,G,SMD0603 | TAIYO ELECTRIC IND.CO.LTD | EMK107BC6106MA-T |  | PWA BOM | In Old BOM |
| 4 | PBFC28,PBEC28,PAFC28,PAEC28,PBMC29,PBFC29,PBEC29,PBAC29,PAMC29,PAFC29,PAEC29,PAAC29,PBMC30,PBFC30,PBEC30,PBAC30,PAMC30,PAFC30,PAEC30,PAAC30,PBMC31,PBFC31,PBEC31,PBAC31,PAMC31,PAFC31,PAEC31,PAAC31,PBMC32,PBFC32,PBEC32,PBAC32,PAMC32,PAFC32,PAEC32,PAAC32,PBMC33,PBFC33,PBEC33,PBAC33,PAMC33,PAFC33,PAEC33,PAAC33,PBMC34,PBFC34,PBEC34,PBAC34,PAMC34,PAFC34,PAEC34,PAAC34,PBMC35,PBFC35,PBEC35,PBAC35,PAMC35,PAFC35,PAEC35,PAAC35,PBMC36,PBFC36,PBEC36,PBAC36,PAMC36,PAFC36,PAEC36,PAAC36,PBMC37,PBFC37,PBEC37,PBAC37,PAMC37,PAFC37,PAEC37,PAAC37,PBMC38,PBFC38,PBEC38,PBAC38,PAMC38,PAFC38,PAEC38,PAAC38,PBMC39,PBFC39,PBEC39,PBAC39,PAMC39,PAFC39,PAEC39,PAAC39,PBMC40,PBFC40,PBEC40,PBAC40,PAMC40,PAFC40,PAEC40,PAAC40,PBMC41,PBFC41,PBEC41,PBAC41,PAMC41,PAFC41,PAEC41,PAAC41,PBMC42,PBFC42,PBEC42,PBAC42,PAMC42,PAFC42,PAEC42,PAAC42,PBMC43,PBFC43,PBEC43,PBAC43,PAMC43,PAFC43,PAEC43,PAAC43,PBMC44,PBFC44,PBEC44,PBAC44,PAMC44,PAFC44,PAEC44,PAAC44,PBMC45,PBFC45,PBEC45,PBAC45,PAMC45,PAFC45,PAEC45,PAAC45,PBMC46,PBFC46,PBEC46,PBAC46,PAMC46,PAFC46,PAEC46,PAAC46,PBMC47,PBFC47,PBEC47,PBAC47,PAMC47,PAFC47,PAEC47,PAAC47,PBMC48,PBFC48,PBEC48,PBAC48,PAMC48,PAFC48,PAEC48,PAAC48,PBMC49,PBFC49,PBEC49,PBAC49,PAMC49,PAFC49,PAEC49,PAAC49,PBMC50,PBFC50,PBEC50,PBAC50,PAMC50,PAFC50,PAEC50,PAAC50,PBMC51,PBFC51,PBEC51,PBAC51,PAMC51,PAFC51,PAEC51,PAAC51,PBMC52,PBFC52,PBEC52,PBAC52,PAMC52,PAFC52,PAEC52,PAAC52,PBMC53,PBFC53,PBEC53,PBAC53,PAMC53,PAFC53,PAEC53,PAAC53,PBMC54,PBFC54,PBEC54,PBAC54,PAMC54,PAFC54,PAEC54,PAAC54,PBMC55,PBFC55,PBEC55,PBAC55,PAMC55,PAFC55,PAEC55,PAAC55,PBMC56,PBFC56,PBEC56,PBAC56,PAMC56,PAFC56,PAEC56,PAAC56,PBMC57,PBFC57,PBEC57,PBAC57,PAMC57,PAFC57,PAEC57,PAAC57,PBMC58,PBAC58,PAMC58,PAAC58,PBAC59,PAAC59,PBAC60,PAAC60,PBAC61,PAAC61,PBFC62,PBEC62,PBAC62,PAFC62,PAEC62,PAAC62,PBMC63,PBFC63,PBEC63,PBAC63,PAMC63,PAFC63,PAEC63,PAAC63,PBMC64,PBFC64,PBEC64,PBAC64,PAMC64,PAFC64,PAEC64,PAAC64,PBMC65,PBFC65,PBEC65,PBAC65,PAMC65,PAFC65,PAEC65,PAAC65,PBMC66,PBFC66,PBEC66,PBAC66,PAMC66,PAFC66,PAEC66,PAAC66,PBMC67,PBFC67,PBEC67,PBAC67,PAMC67,PAFC67,PAEC67,PAAC67,PBMC68,PBFC68,PBEC68,PBAC68,PAMC68,PAFC68,PAEC68,PAAC68,PBMC69,PBFC69,PBEC69,PBAC69,PAMC69,PAFC69,PAEC69,PAAC69,PBMC70,PBFC70,PBEC70,PBAC70,PAMC70,PAFC70,PAEC70,PAAC70,PBMC71,PBFC71,PBEC71,PBAC71,PAMC71,PAFC71,PAEC71,PAAC71,PBMC72,PBAC72,PAMC72,PAAC72,PBAC73,PAAC73,PBAC74,PAAC74,PBAC75,PAAC75,PBAC76,PAAC76,PBAC77,PAAC77,PBAC78,PAAC78,PBAC81,PAAC81,PBAC82,PAAC82,PBAC83,PAAC83,PBAC84,PAAC84,PBAC85,PAAC85,PBAC86,PAAC86,PBAC87,PAAC87,PBAC88,PAAC88,PBAC89,PAAC89,PBAC90,PAAC90,PBAC91,PAAC91,PBAC92,PAAC92,PBAC93,PAAC93,PBAC94,PAAC94,PBAC95,PAAC95,PBAC96,PAAC96,PBAC97,PAAC97,PBAC98,PAAC98,PBAC99,PAAC99,PBAC100,PAAC100,PBAC101,PAAC101,PBAC102,PAAC102,PBAC103,PAAC103,PBAC104,PAAC104,PBAC105,PAAC105,PBAC106,PAAC106,PBAC107,PAAC107,PBAC108,PAAC108,PBAC109,PAAC109,PBAC110,PAAC110,PBAC113,PAAC113,PBAC114,PAAC114,PBAC115,PAAC115,PBAC116,PAAC116,PBAC117,PAAC117,PBAC118,PAAC118,PBAC119,PAAC119,PBAC120,PAAC120,PBAC121,PAAC121,PBAC122,PAAC122,PBAC127,PAAC127,PBAC128,PAAC128,PBAC129,PAAC129,PBAC130,PAAC130,PBAC131,PAAC131,PBAC132,PAAC132,PBAC133,PAAC133,PBAC134,PAAC134,PBAC135,PAAC135,PBAC136,PAAC136,PBAC137,PAAC137,PBAC138,PAAC138,PBAC139,PAAC139,PBAC140,PAAC140,PBAC141,PAAC141,PBAC142,PAAC142,PBAC143,PAAC143,PBAC144,PAAC144,PBAC145,PAAC145,PBAC146,PAAC146,PBAC147,PAAC147,PBAC148,PAAC148,PBAC149,PAAC149,PBAC150,PAAC150,PBAC151,PAAC151,PBAC152,PAAC152,PBAC153,PAAC153,PBAC154,PAAC154,PBAC155,PAAC155,PBAC156,PAAC156,PBFC501,PBEC501,PAFC501,PAEC501,C2168,C2169,C2170,C2172,C2173,C2174,C2175,C2176,C2177,C2178,C2179 | 495 | 62012PS00-015-G | CAP,10uF,+/-20%,X6S,4V,G,SMD0402 | MURATA ELEC. NORTH AMERICA | GRM155C80G106M |  | PWA BOM | In New BOM |
|  |  |  | 62012PS00-023-G | CAP,10uF,+/-20%,X6S,4V,G,SMD0402 | TAIYO ELECTRIC IND.CO.LTD | AMK105CC6106MV-F |  | PWA BOM | In New BOM |
|  |  |  | 62012PS00-026-G | CAP,10uF,+/-20%,X6S,4V,G,SMD0402 | SAMSUNG | CL05X106MR5NUNC |  | PWA BOM | In New BOM |
|  | PBFC28,PBEC28,PAFC28,PAEC28,PBMC29,PBFC29,PBEC29,PBAC29,PAMC29,PAFC29,PAEC29,PAAC29,PBMC30,PBFC30,PBEC30,PBAC30,PAMC30,PAFC30,PAEC30,PAAC30,PBMC31,PBFC31,PBEC31,PBAC31,PAMC31,PAFC31,PAEC31,PAAC31,PBMC32,PBFC32,PBEC32,PBAC32,PAMC32,PAFC32,PAEC32,PAAC32,PBMC33,PBFC33,PBEC33,PBAC33,PAMC33,PAFC33,PAEC33,PAAC33,PBMC34,PBFC34,PBEC34,PBAC34,PAMC34,PAFC34,PAEC34,PAAC34,PBMC35,PBFC35,PBEC35,PBAC35,PAMC35,PAFC35,PAEC35,PAAC35,PBMC36,PBFC36,PBEC36,PBAC36,PAMC36,PAFC36,PAEC36,PAAC36,PBMC37,PBFC37,PBEC37,PBAC37,PAMC37,PAFC37,PAEC37,PAAC37,PBMC38,PBFC38,PBEC38,PBAC38,PAMC38,PAFC38,PAEC38,PAAC38,PBMC39,PBFC39,PBEC39,PBAC39,PAMC39,PAFC39,PAEC39,PAAC39,PBMC40,PBFC40,PBEC40,PBAC40,PAMC40,PAFC40,PAEC40,PAAC40,PBMC41,PBFC41,PBEC41,PBAC41,PAMC41,PAFC41,PAEC41,PAAC41,PBMC42,PBFC42,PBEC42,PBAC42,PAMC42,PAFC42,PAEC42,PAAC42,PBMC43,PBFC43,PBEC43,PBAC43,PAMC43,PAFC43,PAEC43,PAAC43,PBMC44,PBFC44,PBEC44,PBAC44,PAMC44,PAFC44,PAEC44,PAAC44,PBMC45,PBFC45,PBEC45,PBAC45,PAMC45,PAFC45,PAEC45,PAAC45,PBMC46,PBFC46,PBEC46,PBAC46,PAMC46,PAFC46,PAEC46,PAAC46,PBMC47,PBFC47,PBEC47,PBAC47,PAMC47,PAFC47,PAEC47,PAAC47,PBMC48,PBFC48,PBEC48,PBAC48,PAMC48,PAFC48,PAEC48,PAAC48,PBMC49,PBFC49,PBEC49,PBAC49,PAMC49,PAFC49,PAEC49,PAAC49,PBMC50,PBFC50,PBEC50,PBAC50,PAMC50,PAFC50,PAEC50,PAAC50,PBMC51,PBFC51,PBEC51,PBAC51,PAMC51,PAFC51,PAEC51,PAAC51,PBMC52,PBFC52,PBEC52,PBAC52,PAMC52,PAFC52,PAEC52,PAAC52,PBMC53,PBFC53,PBEC53,PBAC53,PAMC53,PAFC53,PAEC53,PAAC53,PBMC54,PBFC54,PBEC54,PBAC54,PAMC54,PAFC54,PAEC54,PAAC54,PBMC55,PBFC55,PBEC55,PBAC55,PAMC55,PAFC55,PAEC55,PAAC55,PBMC56,PBFC56,PBEC56,PBAC56,PAMC56,PAFC56,PAEC56,PAAC56,PBMC57,PBFC57,PBEC57,PBAC57,PAMC57,PAFC57,PAEC57,PAAC57,PBMC58,PBAC58,PAMC58,PAAC58,PBAC59,PAAC59,PBAC60,PAAC60,PBAC61,PAAC61,PBFC62,PBEC62,PBAC62,PAFC62,PAEC62,PAAC62,PBMC63,PBFC63,PBEC63,PBAC63,PAMC63,PAFC63,PAEC63,PAAC63,PBMC64,PBFC64,PBEC64,PBAC64,PAMC64,PAFC64,PAEC64,PAAC64,PBMC65,PBFC65,PBEC65,PBAC65,PAMC65,PAFC65,PAEC65,PAAC65,PBMC66,PBFC66,PBEC66,PBAC66,PAMC66,PAFC66,PAEC66,PAAC66,PBMC67,PBFC67,PBEC67,PBAC67,PAMC67,PAFC67,PAEC67,PAAC67,PBMC68,PBFC68,PBEC68,PBAC68,PAMC68,PAFC68,PAEC68,PAAC68,PBMC69,PBFC69,PBEC69,PBAC69,PAMC69,PAFC69,PAEC69,PAAC69,PBMC70,PBFC70,PBEC70,PBAC70,PAMC70,PAFC70,PAEC70,PAAC70,PBMC71,PBFC71,PBEC71,PBAC71,PAMC71,PAFC71,PAEC71,PAAC71,PBMC72,PBAC72,PAMC72,PAAC72,PBAC73,PAAC73,PBAC74,PAAC74,PBAC75,PAAC75,PBAC76,PAAC76,PBAC77,PAAC77,PBAC78,PAAC78,PBAC81,PAAC81,PBAC82,PAAC82,PBAC83,PAAC83,PBAC84,PAAC84,PBAC85,PAAC85,PBAC86,PAAC86,PBAC87,PAAC87,PBAC88,PAAC88,PBAC89,PAAC89,PBAC90,PAAC90,PBAC91,PAAC91,PBAC92,PAAC92,PBAC93,PAAC93,PBAC94,PAAC94,PBAC95,PAAC95,PBAC96,PAAC96,PBAC97,PAAC97,PBAC98,PAAC98,PBAC99,PAAC99,PBAC100,PAAC100,PBAC101,PAAC101,PBAC102,PAAC102,PBAC103,PAAC103,PBAC104,PAAC104,PBAC105,PAAC105,PBAC106,PAAC106,PBAC107,PAAC107,PBAC108,PAAC108,PBAC109,PAAC109,PBAC110,PAAC110,PBAC113,PAAC113,PBAC114,PAAC114,PBAC115,PAAC115,PBAC116,PAAC116,PBAC117,PAAC117,PBAC118,PAAC118,PBAC119,PAAC119,PBAC120,PAAC120,PBAC121,PAAC121,PBAC122,PAAC122,PBAC127,PAAC127,PBAC128,PAAC128,PBAC129,PAAC129,PBAC130,PAAC130,PBAC131,PAAC131,PBAC132,PAAC132,PBAC133,PAAC133,PBAC134,PAAC134,PBAC135,PAAC135,PBAC136,PAAC136,PBAC137,PAAC137,PBAC138,PAAC138,PBAC139,PAAC139,PBAC140,PAAC140,PBAC141,PAAC141,PBAC142,PAAC142,PBAC143,PAAC143,PBAC144,PAAC144,PBAC145,PAAC145,PBAC146,PAAC146,PBAC147,PAAC147,PBAC148,PAAC148,PBAC149,PAAC149,PBAC150,PAAC150,PBAC151,PAAC151,PBAC152,PAAC152,PBAC153,PAAC153,PBAC154,PAAC154,PBAC155,PAAC155,PBAC156,PAAC156,C225,C226,C264,C273,PBFC501,PBEC501,PAFC501,PAEC501,C2168,C2169,C2170,C2171,C2172,C2173,C2174,C2175,C2176,C2177,C2178,C2179 | 500 | 62012PS00-015-G | CAP,10uF,+/-20%,X6S,4V,G,SMD0402 | MURATA ELEC. NORTH AMERICA | GRM155C80G106M |  | PWA BOM | In Old BOM |
|  |  |  | 62012PS00-023-G | CAP,10uF,+/-20%,X6S,4V,G,SMD0402 | TAIYO ELECTRIC IND.CO.LTD | AMK105CC6106MV-F |  | PWA BOM | In Old BOM |
| 5 | PBMC1,PBFC1,PBEC1,PBAC1,PAMC1,PAFC1,PAEC1,PAAC1,PBMC2,PBFC2,PBEC2,PBAC2,PAMC2,PAFC2,PAEC2,PAAC2,PBMC22,PBFC22,PBEC22,PBAC22,PAMC22,PAFC22,PAEC22,PAAC22,PBMC450,PBFC450,PBEC450,PBAC450,PAMC450,PAFC450,PAEC450,PAAC450,PBAC452,PAAC452 | 34 | 62012RJ00-015-G | CAP,4.7uF,+/-10%,X6S,16V,G,SMD0603 | MURATA ELEC. NORTH AMERICA | GRM188C81C475K |  | PWA BOM | In New BOM |
|  |  |  | 62012RJ00-023-G | CAP,4.7uF,+/-10%,X6S,16V,G,SMD0603 | TAIYO ELECTRIC IND.CO.LTD | EMK107BC6475KA-T |  | PWA BOM | In New BOM |
|  |  |  | 62012RJ02-026-G | CAP,4.7uF,+/-10%,X6S,16V,G,SMD0603 | SAMSUNG | CL10X475KO8NRNC |  | PWA BOM | In New BOM |
|  | PBMC1,PBFC1,PBEC1,PBAC1,PAMC1,PAFC1,PAEC1,PAAC1,PBMC2,PBFC2,PBEC2,PBAC2,PAMC2,PAFC2,PAEC2,PAAC2,PBMC22,PBFC22,PBEC22,PBAC22,PAMC22,PAFC22,PAEC22,PAAC22,PBMC450,PBFC450,PBEC450,PBAC450,PAMC450,PAFC450,PAEC450,PAAC450,PBAC452,PAAC452 | 34 | 62012RJ00-015-G | CAP,4.7uF,+/-10%,X6S,16V,G,SMD0603 | MURATA ELEC. NORTH AMERICA | GRM188C81C475K |  | PWA BOM | In Old BOM |
|  |  |  | 62012RJ00-023-G | CAP,4.7uF,+/-10%,X6S,16V,G,SMD0603 | TAIYO ELECTRIC IND.CO.LTD | EMK107BC6475KA-T |  | PWA BOM | In Old BOM |
| 6 | PBFC59,PBEC59,PAFC59,PAEC59,PBMC60,PAMC60,PBAC124,PAAC124 | 8 | 62010WW01-015-G | CAP,1.8nF,+/-10%,X7R,50V,G,SMD0402 | MURATA ELEC. NORTH AMERICA | GRM155R71H182KA01D |  | PWA BOM | In New BOM |
|  |  |  | 62010WW00-026-G | CAP,1.8nF,+/-10%,X7R,50V,G,SMD0402 | SAMSUNG | CL05B182KB5NNNC |  | PWA BOM | In New BOM |
|  | PBFC59,PBEC59,PAFC59,PAEC59,PBMC60,PAMC60,PBAC124,PAAC124 | 8 | 62010WW01-015-G | CAP,1.8nF,+/-10%,X7R,50V,G,SMD0402 | MURATA ELEC. NORTH AMERICA | GRM155R71H182KA01D |  | PWA BOM | In Old BOM |
| 7 | PBMQ11,PBAQ11,PAMQ11,PAAQ11,PBFQ12,PBEQ12,PAFQ12,PAEQ12,Q8,PHAQ8,Q85,Q86,Q87,Q88,Q89,Q90,Q91,Q92 | 18 | 510100W00-237-G | TRANS N,MMBT3904-7-F,40V,0.2A,G,SOT23-3,SMD | DIODES INCORPORATION | MMBT3904-7-F |  | PWA BOM | In New BOM |
|  |  |  | 510101700-185-G | TRANS N,MMBT3904,40V,0.2A,G,SOT23-3,SMD | FAIRCHILD SEMICONDUCTOR CORP | MMBT3904 |  | PWA BOM | In New BOM |
|  | Q8,PHAQ8,Q85,Q86,Q87,Q88,Q89,Q90,Q91,Q92 | 10 | 510100W00-237-G | TRANS N,MMBT3904-7-F,40V,0.2A,G,SOT23-3,SMD | DIODES INCORPORATION | MMBT3904-7-F |  | PWA BOM | In Old BOM |
| 8 | PBER7,PAMR7,PAMR8,PAFR9,PAFR10,PAER10,PBAR11,PAER11,PBFR12,PBAR12,PAAR12,PBMR13,PBFR13,PBER14,PAAR14,PBMR15,PBMR17,PBFR17,PBER17,PBAR17,PAMR17,PAFR17,PAER17,PAAR17,PBMR21,PBFR21,PBER21,PBAR21,PAMR21,PAFR21,PAER21,PAAR21,PBMR24,PBFR24,PBER24,PBAR24,PAMR24,PAFR24,PAER24,PAAR24,PBMR27,PBFR27,PBER27,PBAR27,PAMR27,PAFR27,PAER27,PAAR27 | 48 | 61010PS00-017-G | RES,200KOhm,+/-1%,1/16W,G,SMD0402 | KOA SPEER ELECTRONICS, INC. | RK73H1ETTP2003F |  | PWA BOM | In New BOM |
|  |  |  | 61010PS00-029-G | RES,200KOhm,+/-1%,1/16W,G,SMD0402 | VISHAY | CRCW0402200KFKED |  | PWA BOM | In New BOM |
|  | PBER7,PAMR7,PAMR8,PAFR9,PAFR10,PAER10,PBAR11,PAER11,PBFR12,PBAR12,PAAR12,PBMR13,PBFR13,PBER14,PAAR14,PBMR15,PBMR17,PBFR17,PBER17,PBAR17,PAMR17,PAFR17,PAER17,PAAR17,PBMR21,PBFR21,PBER21,PBAR21,PAMR21,PAFR21,PAER21,PAAR21,PBMR24,PBFR24,PBER24,PBAR24,PAMR24,PAFR24,PAER24,PAAR24,PBMR27,PBFR27,PBER27,PBAR27,PAMR27,PAFR27,PAER27,PAAR27 | 48 | 61010PS00-017-G | RES,200KOhm,+/-1%,1/16W,G,SMD0402 | KOA SPEER ELECTRONICS, INC. | RK73H1ETTP2003F |  | PWA BOM | In Old BOM |
| 9 | PBAR26,PAAR26 | 2 | 61100YD00-017-G | RES,9.53KOhm,+/-0.1%,1/16W,G,SMD0402 | KOA SPEER ELECTRONICS, INC. | RN731ETTP9531B25 |  | PWA BOM | In New BOM |
|  |  |  | 61100YD00-024-G | RES,9.53KOhm,+/-0.1%,1/16W,G,SMD0402 | PANASONIC | ERA2AEB9531X |  | PWA BOM | In New BOM |
|  | PBAR26,PAAR26 | 2 | 61100YD00-017-G | RES,9.53KOhm,+/-0.1%,1/16W,G,SMD0402 | KOA SPEER ELECTRONICS, INC. | RN731ETTP9531B25 |  | PWA BOM | In Old BOM |
| 10 | PBMR107,PAMR107,PBER109,PAFR109,PAER109,PBFR110,PBAR113,PAAR113 | 8 | 61011B300-017-G | RES,1MOhm,+/-1%,1/16W,G,SMD0402 | KOA SPEER ELECTRONICS, INC. | RK73H1ETTP1004F |  | PWA BOM | In New BOM |
|  |  |  | 61011B300-029-G | RES,1MOhm,+/-1%,1/16W,G,SMD0402 | VISHAY | CRCW04021M00FKED |  | PWA BOM | In New BOM |
|  | PBMR107,PAMR107,PBER109,PAFR109,PAER109,PBFR110,PBAR113,PAAR113 | 8 | 61011B300-017-G | RES,1MOhm,+/-1%,1/16W,G,SMD0402 | KOA SPEER ELECTRONICS, INC. | RK73H1ETTP1004F |  | PWA BOM | In Old BOM |
| 11 | PBMR109,PAMR109,PBER111,PAFR111,PAER111,PBFR112,PBAR115,PAAR115 | 8 | 61011GU00-017-G | RES,274 Ohm,+/-1%,1/16W,G,SMD0402 | KOA SPEER ELECTRONICS, INC. | RK73H1ETTP2740F |  | PWA BOM | In New BOM |
|  |  |  | 61011GU00-029-G | RES,274 Ohm,+/-1%,1/16W,G,SMD0402 | VISHAY | CRCW0402274RFKED |  | PWA BOM | In New BOM |
|  | PBMR109,PAMR109,PBER111,PAFR111,PAER111,PBFR112,PBAR115,PAAR115 | 8 | 61011GU00-017-G | RES,274 Ohm,+/-1%,1/16W,G,SMD0402 | KOA SPEER ELECTRONICS, INC. | RK73H1ETTP2740F |  | PWA BOM | In Old BOM |
| 12 | PBMR117,PAMR117,PBER119,PAFR119,PAER119,PBFR120,PBAR123,PAAR123 | 8 | 610114P00-017-G | RES,715 Ohm,+/-1%,1/16W,G,SMD0402 | KOA SPEER ELECTRONICS, INC. | RK73H1ETTP7150F |  | PWA BOM | In New BOM |
|  |  |  | 610114P00-024-G | RES,715 Ohm,+/-1%,1/16W,G,SMD0402 | PANASONIC | ERJ2RKF7150X |  | PWA BOM | In New BOM |
|  | PBMR117,PAMR117,PBER119,PAFR119,PAER119,PBFR120,PBAR123,PAAR123 | 8 | 610114P00-017-G | RES,715 Ohm,+/-1%,1/16W,G,SMD0402 | KOA SPEER ELECTRONICS, INC. | RK73H1ETTP7150F |  | PWA BOM | In Old BOM |
| 13 | PHAR79,PBMR118,PAMR118,PBER120,PAFR120,PAER120,PBFR121,PBAR124,PAAR124 | 9 | 61011L200-017-G | RES,3.65KOhm,+/-1%,1/16W,G,SMD0402 | KOA SPEER ELECTRONICS, INC. | RK73H1ETTP3651F |  | PWA BOM | In New BOM |
|  |  |  | 61011L200-029-G | RES,3.65KOhm,+/-1%,1/16W,G,SMD0402 | VISHAY | 61011L200-029-G |  | PWA BOM | In New BOM |
|  | PHAR79,PBMR118,PAMR118,PBER120,PAFR120,PAER120,PBFR121,PBAR124,PAAR124 | 9 | 61011L200-017-G | RES,3.65KOhm,+/-1%,1/16W,G,SMD0402 | KOA SPEER ELECTRONICS, INC. | RK73H1ETTP3651F |  | PWA BOM | In Old BOM |
| 14 | PBMR304,PBAR304,PAMR304,PAAR304 | 4 | 61011BH00-017-G | RES,22.1 Ohm,+/-1%,1/16W,G,SMD0402 | KOA SPEER ELECTRONICS, INC. | RK73H1ETTP22R1F |  | PWA BOM | In New BOM |
|  |  |  | 61011BH00-024-G | RES,22.1 Ohm,+/-1%,1/16W,G,SMD0402 | PANASONIC | ERJ2RKF22R1X |  | PWA BOM | In New BOM |
|  |  |  | 61011BH00-029-G | RES,22.1 Ohm,+/-1%,1/16W,G,SMD0402 | VISHAY | CRCW040222R1FKED |  | PWA BOM | In New BOM |
|  | PBMR304,PBAR304,PAMR304,PAAR304 | 4 | 61011BH00-017-G | RES,22.1 Ohm,+/-1%,1/16W,G,SMD0402 | KOA SPEER ELECTRONICS, INC. | RK73H1ETTP22R1F |  | PWA BOM | In Old BOM |
| 15 | PBMR3,PAMR12 | 2 | 61011QD00-017-G | RES,330 Ohm,+/-1%,1/16W,G,SMD0402 | KOA SPEER ELECTRONICS, INC. | RK73H1ETTP3300F |  | PWA BOM | In New BOM |
|  |  |  | 61011QD00-029-G | RES,330 Ohm,+/-1%,1/16W,G,SMD0402 | VISHAY | CRCW0402330RFKED |  | PWA BOM | In New BOM |
|  | PBMR3,PAMR12 | 2 | 61011QD00-017-G | RES,330 Ohm,+/-1%,1/16W,G,SMD0402 | KOA SPEER ELECTRONICS, INC. | RK73H1ETTP3300F |  | PWA BOM | In Old BOM |
| 16 | PBNR17,PANR17 | 2 | 61011B600-017-G | RES,5.36KOhm,+/-1%,1/16W,G,SMD0402 | KOA SPEER ELECTRONICS, INC. | RK73H1ETTP5361F |  | PWA BOM | In New BOM |
|  |  |  | 61011B600-024-G | RES,5.36KOhm,+/-1%,1/16W,G,SMD0402 | PANASONIC | ERJ2RKF5361X |  | PWA BOM | In New BOM |
|  |  |  | 61011B600-029-G | RES,5.36KOhm,+/-1%,1/16W,G,SMD0402 | VISHAY | CRCW04025K36FKEDC |  | PWA BOM | In New BOM |
|  | PBNR17,PANR17 | 2 | 61011B600-017-G | RES,5.36KOhm,+/-1%,1/16W,G,SMD0402 | KOA SPEER ELECTRONICS, INC. | RK73H1ETTP5361F |  | PWA BOM | In Old BOM |
| 17 | PSRR20,PBNR23,PANR23,PHAR28,PHAR29,PHAR30,R668,R669,R683,R762,R763,R764,R765,R766,R767,R769,R770,R772,R773,R774,R775,R776,R777,R778,R779,R780,R781,R782,R783,R784,R786,R787,R788,R791,R795,R800,R801,R804,R805,R806,R807,R808,R809,R811,R814,R817,R820,R822,R823,R825,R827,R828,R830,R893,R894,R901,R902,R922,R942,R943,R944,R945,R949,R950,R955,R956,R957,R958,R959,R1129,R1135,R1138,R1148,R1149,R1150,R1151,R1152,R1156,R1159,R1162,R1164,R1165,R1172,R1174,R1175,R1176,R1184,R1185,R1186,R1190,R1195,R1197,R1198,R1199,R1210,R1211,R1212,R1213,R1218,R1219,R1220,R1221,R1222,R1223,R1224,R1240,R1256,R1257,R1263,R1267,R1271,R1275,R1295,R1296,R1460,R1461,R1462,R1463,R1464,R1465,R1466,R1467,R1468,R1469,R1470,R1471,R1474,R1475,R1476,R1477,R1495,R1504,R1507,R1508,R1509,R1511,R1512,R1515,R1520,R1521,R1589,R1590,R1592,R1593,R1603,R1604,R1605,R1606,R1779,R1780,R1781,R1782,R1786,R1789,R1801,R1820,R1821,R1834 | 158 | 61010LA00-017-G | RES,4.7KOhm,+/-1%,1/16W,G,SMD0402 | KOA SPEER ELECTRONICS, INC. | RK73H1ETTP4701F |  | PWA BOM | In New BOM |
|  |  |  | 61010LA00-029-G | RES,4.7KOhm,+/-1%,1/16W,G,SMD0402 | VISHAY | CRCW04024K70FKED |  | PWA BOM | In New BOM |
|  | PSRR20,PBNR23,PANR23,PHAR28,PHAR29,PHAR30,R668,R669,R683,R762,R763,R764,R765,R766,R767,R769,R770,R772,R773,R774,R775,R776,R777,R778,R779,R780,R781,R782,R783,R784,R786,R787,R788,R791,R795,R800,R801,R804,R805,R806,R807,R808,R809,R811,R814,R817,R820,R822,R823,R825,R827,R828,R830,R893,R894,R901,R902,R922,R942,R943,R944,R945,R949,R950,R955,R956,R957,R958,R959,R1129,R1135,R1138,R1148,R1149,R1150,R1151,R1152,R1156,R1159,R1162,R1164,R1165,R1172,R1174,R1175,R1176,R1184,R1185,R1186,R1190,R1195,R1197,R1198,R1199,R1210,R1211,R1212,R1213,R1218,R1219,R1220,R1221,R1222,R1223,R1224,R1240,R1256,R1257,R1263,R1267,R1271,R1275,R1295,R1296,R1460,R1461,R1462,R1463,R1464,R1465,R1466,R1467,R1468,R1469,R1470,R1471,R1474,R1475,R1476,R1477,R1495,R1504,R1507,R1508,R1509,R1511,R1512,R1515,R1520,R1521,R1589,R1590,R1592,R1593,R1603,R1604,R1605,R1606,R1779,R1780,R1781,R1782,R1786,R1789,R1801,R1820,R1821,R1834 | 158 | 61010LA00-017-G | RES,4.7KOhm,+/-1%,1/16W,G,SMD0402 | KOA SPEER ELECTRONICS, INC. | RK73H1ETTP4701F |  | PWA BOM | In Old BOM |
| 18 | PANR26 | 1 | 61011BS00-017-G | RES,2.05KOhm,+/-1%,1/16W,G,SMD0402 | KOA SPEER ELECTRONICS, INC. | RK73H1ETTP2051F |  | PWA BOM | In New BOM |
|  |  |  | 61011BS00-029-G | RES,2.05KOhm,+/-1%,1/16W,G,SMD0402 | VISHAY | CRCW04022K05FKED |  | PWA BOM | In New BOM |
|  | PANR26 | 1 | 61011BS00-017-G | RES,2.05KOhm,+/-1%,1/16W,G,SMD0402 | KOA SPEER ELECTRONICS, INC. | RK73H1ETTP2051F |  | PWA BOM | In Old BOM |
| 19 | PBNR26 | 1 | 610118R00-017-G | RES,1.54KOhm,+/-1%,1/16W,G,SMD0402 | KOA SPEER ELECTRONICS, INC. | RK73H1ETTP1541F |  | PWA BOM | In New BOM |
|  |  |  | 610118R00-029-G | RES,1.54KOhm,+/-1%,1/16W,G,SMD0402 | VISHAY | CRCW04021K54FKED |  | PWA BOM | In New BOM |
|  | PBNR26 | 1 | 610118R00-017-G | RES,1.54KOhm,+/-1%,1/16W,G,SMD0402 | KOA SPEER ELECTRONICS, INC. | RK73H1ETTP1541F |  | PWA BOM | In Old BOM |
| 20 | PUAR2,PSAR2,PRAR2,PQAR2,PPAR2,PIAR2,PFAR2,PEAR2 | 8 | 610114200-017-G | RES,10.7KOhm,+/-1%,1/16W,G,SMD0402 | KOA SPEER ELECTRONICS, INC. | RK73H1ETTP1072F |  | PWA BOM | In New BOM |
|  |  |  | 610114200-024-G | RES,10.7KOhm,+/-1%,1/16W,G,SMD0402 | PANASONIC | ERJ2RKF1072X |  | PWA BOM | In New BOM |
|  |  |  | 610114200-029-G | RES,10.7KOhm,+/-1%,1/16W,G,SMD0402 | VISHAY | CRCW040210K7FKED |  | PWA BOM | In New BOM |
|  | PUAR2,PSAR2,PRAR2,PQAR2,PPAR2,PIAR2,PFAR2,PEAR2 | 8 | 610114200-017-G | RES,10.7KOhm,+/-1%,1/16W,G,SMD0402 | KOA SPEER ELECTRONICS, INC. | RK73H1ETTP1072F |  | PWA BOM | In Old BOM |
| 21 | PUAR4,PSAR4,PRAR4,PQAR4,PPAR4,PIAR4,PFAR4,PEAR4,PUAR6,PSAR6,PRAR6,PQAR6,PPAR6,PIAR6,PFAR6,PEAR6 | 16 | 611004D00-017-G | RES,1.5KOhm,+/-0.1%,1/16W,G,SMD0402 | KOA SPEER ELECTRONICS, INC. | RN731ETTP1501B25 |  | PWA BOM | In New BOM |
|  |  |  | 611004D00-029-G | RES,1.5KOhm,+/-0.1%,1/16W,G,SMD0402 | VISHAY | TNPW04021K50BEED |  | PWA BOM | In New BOM |
|  | PUAR4,PSAR4,PRAR4,PQAR4,PPAR4,PIAR4,PFAR4,PEAR4,PUAR6,PSAR6,PRAR6,PQAR6,PPAR6,PIAR6,PFAR6,PEAR6 | 16 | 611004D00-017-G | RES,1.5KOhm,+/-0.1%,1/16W,G,SMD0402 | KOA SPEER ELECTRONICS, INC. | RN731ETTP1501B25 |  | PWA BOM | In Old BOM |
| 22 | PUAR10,PSAR10,PRAR10,PQAR10,PPAR10,PIAR10,PFAR10,PEAR10 | 8 | 610128200-017-G | RES,26.1 Ohm,+/-1%,1/16W,G,SMD0402 | KOA SPEER ELECTRONICS, INC. | RK73H1ETTP26R1F |  | PWA BOM | In New BOM |
|  |  |  | 610128200-029-G | RES,26.1 Ohm,+/-1%,1/16W,G,SMD0402 | VISHAY | CRCW040226R1FKED |  | PWA BOM | In New BOM |
|  | PUAR10,PSAR10,PRAR10,PQAR10,PPAR10,PIAR10,PFAR10,PEAR10 | 8 | 610128200-017-G | RES,26.1 Ohm,+/-1%,1/16W,G,SMD0402 | KOA SPEER ELECTRONICS, INC. | RK73H1ETTP26R1F |  | PWA BOM | In Old BOM |
| 23 | PSLC16,PSFC16,PSEC16,PSDC16,PEEC16,PEDC16 | 6 | 62012CM01-015-G | CAP,10uF,+/-20%,X6S,4V,G,SMD0603 | MURATA ELEC. NORTH AMERICA | GRM188C80G106M |  | PWA BOM | In New BOM |
|  |  |  | 62012CM00-026-G | CAP,10uF,+/-20%,X6S,4V,G,SMD0603 | SAMSUNG | CL10X106MR8NNNC |  | PWA BOM | In New BOM |
|  | PSLC16,PSFC16,PSEC16,PSDC16,PEEC16,PEDC16 | 6 | 62012CM01-015-G | CAP,10uF,+/-20%,X6S,4V,G,SMD0603 | MURATA ELEC. NORTH AMERICA | GRM188C80G106M |  | PWA BOM | In Old BOM |
| 24 | PSLR17,PSFR17,PSER17,PSDR17,PQPR17,PFRR17,PEER17,PEDR17,PEDR19 | 9 | 611004M00-017-G | RES,16.5KOhm,+/-0.1%,1/16W,G,SMD0402 | KOA SPEER ELECTRONICS, INC. | RN731ETTP1652B25 |  | PWA BOM | In New BOM |
|  |  |  | 611004M00-024-G | RES,16.5KOhm,+/-0.1%,1/16W,G,SMD0402 | PANASONIC | ERA2AEB1652X |  | PWA BOM | In New BOM |
|  | PSLR17,PSFR17,PSER17,PSDR17,PQPR17,PFRR17,PEER17,PEDR17,PEDR19 | 9 | 611004M00-017-G | RES,16.5KOhm,+/-0.1%,1/16W,G,SMD0402 | KOA SPEER ELECTRONICS, INC. | RN731ETTP1652B25 |  | PWA BOM | In Old BOM |
| 25 | PSPR5,PIPR5,PFPR5,PEPR5 | 4 | 61011H300-017-G | RES,316 Ohm,+/-1%,1/16W,G,SMD0402 | KOA SPEER ELECTRONICS, INC. | RK73H1ETTP3160F |  | PWA BOM | In New BOM |
|  |  |  | 61011H300-029-G | RES,316 Ohm,+/-1%,1/16W,G,SMD0402 | VISHAY | CRCW0402316RFKEDC |  | PWA BOM | In New BOM |
|  | PSPR5,PIPR5,PFPR5,PEPR5 | 4 | 61011H300-017-G | RES,316 Ohm,+/-1%,1/16W,G,SMD0402 | KOA SPEER ELECTRONICS, INC. | RK73H1ETTP3160F |  | PWA BOM | In Old BOM |
| 26 | PERR2,PHAR35 | 2 | 61011PE00-017-G | RES,8.87KOhm,+/-1%,1/16W,G,SMD0402 | KOA SPEER ELECTRONICS, INC. | RK73H1ETTP8871F |  | PWA BOM | In New BOM |
|  |  |  | 61011PE00-024-G | RES,8.87KOhm,+/-1%,1/16W,G,SMD0402 | VISHAY | ERJ2RKF8871X |  | PWA BOM | In New BOM |
|  |  |  | 61011PE00-029-G | RES,8.87KOhm,+/-1%,1/16W,G,SMD0402 | PANASONIC | CRCW04028K87FKEDC |  | PWA BOM | In New BOM |
|  | PERR2,PHAR35 | 2 | 61011PE00-017-G | RES,8.87KOhm,+/-1%,1/16W,G,SMD0402 | KOA SPEER ELECTRONICS, INC. | RK73H1ETTP8871F |  | PWA BOM | In Old BOM |
| 27 | PFRR1 | 1 | 61011R400-017-G | RES,34.8KOhm,+/-1%,1/16W,G,SMD0402 | KOA SPEER ELECTRONICS, INC. | RK73H1ETTP3482F |  | PWA BOM | In New BOM |
|  |  |  | 61011R400-024-G | RES,34.8KOhm,+/-1%,1/16W,G,SMD0402 | PANASONIC | ERJ2RKF3482X |  | PWA BOM | In New BOM |
|  | PFRR1 | 1 | 61011R400-017-G | RES,34.8KOhm,+/-1%,1/16W,G,SMD0402 | KOA SPEER ELECTRONICS, INC. | RK73H1ETTP3482F |  | PWA BOM | In Old BOM |
| 28 | PHAR6 | 1 | 610100R00-017-G | RES,3.74KOhm,+/-1%,1/10W,G,SMD0603 | KOA SPEER ELECTRONICS, INC. | RK73H1JTTD3741F |  | PWA BOM | In New BOM |
|  |  |  | 610100R00-024-G | RES,3.74KOhm,+/-1%,1/10W,G,SMD0603 | PANASONIC | ERJ3EKF3741V |  | PWA BOM | In New BOM |
|  |  |  | 610100R00-029-G | RES,3.74KOhm,+/-1%,1/10W,G,SMD0603 | VISHAY | CRCW06033K74FKEB |  | PWA BOM | In New BOM |
|  | PHAR6 | 1 | 610100R00-017-G | RES,3.74KOhm,+/-1%,1/10W,G,SMD0603 | KOA SPEER ELECTRONICS, INC. | RK73H1JTTD3741F |  | PWA BOM | In Old BOM |
| 29 | PSIR2 | 1 | 61011MA00-017-G | RES,3.32KOhm,+/-1%,1/16W,G,SMD0402 | KOA SPEER ELECTRONICS, INC. | RK73H1ETTP3321F |  | PWA BOM | In New BOM |
|  |  |  | 61011MA00-024-G | RES,3.32KOhm,+/-1%,1/16W,G,SMD0402 | PANASONIC | ERJ2RKF3321X |  | PWA BOM | In New BOM |
|  |  |  | 61011MA00-029-G | RES,3.32KOhm,+/-1%,1/16W,G,SMD0402 | VISHAY | CRCW04023K32FKED |  | PWA BOM | In New BOM |
|  | PSIR2 | 1 | 61011MA00-017-G | RES,3.32KOhm,+/-1%,1/16W,G,SMD0402 | KOA SPEER ELECTRONICS, INC. | RK73H1ETTP3321F |  | PWA BOM | In Old BOM |
| 30 | PSUQ1,Q2,Q6 | 3 | 51030CQ00-185-G | MOS N,2N7002,60V,115mA,7.5ohm@5V,G,SOT23-3,SMD | FAIRCHILD SEMICONDUCTOR CORP | 2N7002 |  | PWA BOM | In New BOM |
|  |  |  | 510301N00-223-G | MOS N,2N7002LT1G,60V,0.115A,7.5ohm@5V,G,SOT23-3,SMD | ON SEMICONDUCTOR CORP | 2N7002LT1G |  | PWA BOM | In New BOM |
|  | PSUQ1 | 1 | 51030CQ00-185-G | MOS N,2N7002,60V,115mA,7.5ohm@5V,G,SOT23-3,SMD | FAIRCHILD SEMICONDUCTOR CORP | 2N7002 |  | PWA BOM | In Old BOM |
| 31 | R1492 | 1 | 610118800-017-G | RES,499KOhm,+/-1%,1/8W,G,SMD0805 | KOA SPEER ELECTRONICS, INC. | RK73H2ATTD4993F |  | PWA BOM | In New BOM |
|  |  |  | 610118800-024-G | RES,499KOhm,+/-1%,1/8W,G,SMD0805 | PANASONIC | ERJ6ENF4993V |  | PWA BOM | In New BOM |
|  | R1492 | 1 | 610118800-017-G | RES,499KOhm,+/-1%,1/8W,G,SMD0805 | KOA SPEER ELECTRONICS, INC. | RK73H2ATTD4993F |  | PWA BOM | In Old BOM |
| 32 | R1493 | 1 | 61011LF00-017-G | RES,499KOhm,+/-1%,1/16W,G,SMD0402 | KOA SPEER ELECTRONICS, INC. | RK73H1ETTP4993F |  | PWA BOM | In New BOM |
|  |  |  | 61011LF00-024-G | RES,499KOhm,+/-1%,1/16W,G,SMD0402 | PANASONIC | ERJ2RKF4993X |  | PWA BOM | In New BOM |
|  | R1493 | 1 | 61011LF00-017-G | RES,499KOhm,+/-1%,1/16W,G,SMD0402 | KOA SPEER ELECTRONICS, INC. | RK73H1ETTP4993F |  | PWA BOM | In Old BOM |
| 33 | PCB | 1 | 0101EJD00-000-G | PCB,Zaius-MB EVT3-X02,OSP,Red,22L,22.20*13.00,G | GCE | 0101EJD00-000-G |  | PWA BOM | In New BOM |
|  |  |  | 0101EJD00-000-G | PCB,Zaius-MB EVT3-X02,OSP,Red,22L,22.20*13.00,G | ISU | 0101EJD00-000-G |  | PWA BOM | In New BOM |
|  | PCB | 1 | 0101E6K00-000-G | PCB,Zaius-MB EVT2-X01,OSP,Red,22L,22.20*13.00,G | GCE | 0101E6K00-000-G |  | PWA BOM | In Old BOM |
|  |  |  | 0101E6K00-000-G | PCB,Zaius-MB EVT2-X01,OSP,Red,22L,22.20*13.00,G | ISU | 0101E6K00-000-G |  | PWA BOM | In Old BOM |
|  |  |  | 0101E6K00-000-G | PCB,Zaius-MB EVT2-X01,OSP,Red,22L,22.20*13.00,G | FOUNDER | 0101E6K00-000-G |  | PWA BOM | In Old BOM |
| 34 | C2130 | 1 | 620103700-015-G | CAP,100nF,+/-10%,X7R,10V,G,SMD0402 | MURATA ELEC. NORTH AMERICA | GRM155R71A104K |  | PWA BOM | In New BOM |
|  |  |  | 620103700-023-G | CAP,100nF,+/-10%,X7R,10V,G,SMD0402 | TAIYO ELECTRIC IND.CO.LTD | LMK105B7104KV-F |  | PWA BOM | In New BOM |
|  |  |  | 620103700-026-G | CAP,100nF,+/-10%,X7R,10V,G,SMD0402 | SAMSUNG SEMICONDUCTOR | CL05B104KP5NNNC |  | PWA BOM | In New BOM |
|  | C2130 | 1 | 62010G800-015-G | CAP,22nF,+/-10%,X7R,16V,G,SMD0402 | MURATA ELEC. NORTH AMERICA | GRM155R71C223K |  | PWA BOM | In Old BOM |
|  |  |  | 62010G800-026-G | CAP,22nF,+/-10%,X7R,16V,G,SMD0402 | SAMSUNG SEMICONDUCTOR | CL05B223KO5NNNC |  | PWA BOM | In Old BOM |
|  |  |  | 62010G800-023-G | CAP,22nF,+/-10%,X7R,16V,G,SMD0402 | TAIYO ELECTRIC IND.CO.LTD | EMK105B7223KV-F |  | PWA BOM | In Old BOM |
| 35 | C147,C860 | 2 | 62012WD00-015-G | CAP,4.7uF,+/-20%,X6S,6.3V,G,SMD0402 | MURATA ELEC. NORTH AMERICA | GRM155C80J475MEAAD |  | PWA BOM | In New BOM |
|  |  |  | 62012WD00-023-G | CAP,4.7uF,+/-20%,X6S,6.3V,G,SMD0402 | TAIYO ELECTRIC IND.CO.LTD | JMK105BC6475MV-F |  | PWA BOM | In New BOM |
|  | C147,C860 | 2 | 62011DF01-015-G | CAP,220nF,+/-10%,X7R,16V,G,SMD0402 | MURATA ELEC. NORTH AMERICA | GRM155R71C224K |  | PWA BOM | In Old BOM |
|  |  |  | 62011DF00-026-G | CAP,220nF,+/-10%,X7R,16V,G,SMD0402 | SAMSUNG SEMICONDUCTOR | CL05B224KO5NNNC |  | PWA BOM | In Old BOM |
|  |  |  | 62011DF00-023-G | CAP,220nF,+/-10%,X7R,16V,G,SMD0402 | TAIYO ELECTRIC IND.CO.LTD | EMK105B7224KV-FR |  | PWA BOM | In Old BOM |
| 36 | C134,C136,C146,C149,C181,C848,C849,C855,C903 | 9 | 62012NU00-015-G | CAP,1uF,+/-10%,X7R,6.3V,G,SMD0402 | MURATA ELEC. NORTH AMERICA | GRM155R70J105KA12D |  | PWA BOM | In New BOM |
|  |  |  | 62012NU00-026-G | CAP,1uF,+/-10%,X7R,6.3V,G,SMD0402 | SAMSUNG SEMICONDUCTOR | CL05B105KQ5NQNC |  | PWA BOM | In New BOM |
|  | C134,C136,C146,C149,C181,C848,C849,C855,C903 | 9 | 62011DF01-015-G | CAP,220nF,+/-10%,X7R,16V,G,SMD0402 | MURATA ELEC. NORTH AMERICA | GRM155R71C224K |  | PWA BOM | In Old BOM |
|  |  |  | 62011DF00-026-G | CAP,220nF,+/-10%,X7R,16V,G,SMD0402 | SAMSUNG SEMICONDUCTOR | CL05B224KO5NNNC |  | PWA BOM | In Old BOM |
|  |  |  | 62011DF00-023-G | CAP,220nF,+/-10%,X7R,16V,G,SMD0402 | TAIYO ELECTRIC IND.CO.LTD | EMK105B7224KV-FR |  | PWA BOM | In Old BOM |
| 37 | C142,C144,C856,C864 | 4 | 62012P100-015-G | CAP,2.2uF,+/-20%,X7S,10V,G,SMD0402 | MURATA ELEC. NORTH AMERICA | GRM155C71A225M |  | PWA BOM | In New BOM |
|  | C142,C144,C856,C864 | 4 | 62011DF01-015-G | CAP,220nF,+/-10%,X7R,16V,G,SMD0402 | MURATA ELEC. NORTH AMERICA | GRM155R71C224K |  | PWA BOM | In Old BOM |
|  |  |  | 62011DF00-026-G | CAP,220nF,+/-10%,X7R,16V,G,SMD0402 | SAMSUNG SEMICONDUCTOR | CL05B224KO5NNNC |  | PWA BOM | In Old BOM |
|  |  |  | 62011DF00-023-G | CAP,220nF,+/-10%,X7R,16V,G,SMD0402 | TAIYO ELECTRIC IND.CO.LTD | EMK105B7224KV-FR |  | PWA BOM | In Old BOM |
| 38 | C226 | 1 | 62012P100-015-G | CAP,2.2uF,+/-20%,X7S,10V,G,SMD0402 | MURATA ELEC. NORTH AMERICA | GRM155C71A225M |  | PWA BOM | In New BOM |
|  | C226 | 1 | 62012PS00-015-G | CAP,10uF,+/-20%,X6S,4V,G,SMD0402 | MURATA ELEC. NORTH AMERICA | GRM155C80G106M |  | PWA BOM | In Old BOM |
|  |  |  | 62012PS00-023-G | CAP,10uF,+/-20%,X6S,4V,G,SMD0402 | TAIYO ELECTRIC IND.CO.LTD | AMK105CC6106MV-F |  | PWA BOM | In Old BOM |
| 39 | C234 | 1 | 62012P100-015-G | CAP,2.2uF,+/-20%,X7S,10V,G,SMD0402 | MURATA ELEC. NORTH AMERICA | GRM155C71A225M |  | PWA BOM | In New BOM |
|  | C234 | 1 | 620103700-015-G | CAP,100nF,+/-10%,X7R,10V,G,SMD0402 | MURATA ELEC. NORTH AMERICA | GRM155R71A104K |  | PWA BOM | In Old BOM |
|  |  |  | 620103700-023-G | CAP,100nF,+/-10%,X7R,10V,G,SMD0402 | TAIYO ELECTRIC IND.CO.LTD | LMK105B7104KV-F |  | PWA BOM | In Old BOM |
|  |  |  | 620103700-026-G | CAP,100nF,+/-10%,X7R,10V,G,SMD0402 | SAMSUNG SEMICONDUCTOR | CL05B104KP5NNNC |  | PWA BOM | In Old BOM |
| 40 | C203,C235 | 2 | 62011DF01-015-G | CAP,220nF,+/-10%,X7R,16V,G,SMD0402 | MURATA ELEC. NORTH AMERICA | GRM155R71C224K |  | PWA BOM | In New BOM |
|  |  |  | 62011DF00-026-G | CAP,220nF,+/-10%,X7R,16V,G,SMD0402 | SAMSUNG SEMICONDUCTOR | CL05B224KO5NNNC |  | PWA BOM | In New BOM |
|  |  |  | 62011DF00-023-G | CAP,220nF,+/-10%,X7R,16V,G,SMD0402 | TAIYO ELECTRIC IND.CO.LTD | EMK105B7224KV-FR |  | PWA BOM | In New BOM |
|  | C203,C235 | 2 | 620103700-015-G | CAP,100nF,+/-10%,X7R,10V,G,SMD0402 | MURATA ELEC. NORTH AMERICA | GRM155R71A104K |  | PWA BOM | In Old BOM |
|  |  |  | 620103700-023-G | CAP,100nF,+/-10%,X7R,10V,G,SMD0402 | TAIYO ELECTRIC IND.CO.LTD | LMK105B7104KV-F |  | PWA BOM | In Old BOM |
|  |  |  | 620103700-026-G | CAP,100nF,+/-10%,X7R,10V,G,SMD0402 | SAMSUNG SEMICONDUCTOR | CL05B104KP5NNNC |  | PWA BOM | In Old BOM |
| 41 | C206,C245 | 2 | 62011DF01-015-G | CAP,220nF,+/-10%,X7R,16V,G,SMD0402 | MURATA ELEC. NORTH AMERICA | GRM155R71C224K |  | PWA BOM | In New BOM |
|  |  |  | 62011DF00-026-G | CAP,220nF,+/-10%,X7R,16V,G,SMD0402 | SAMSUNG SEMICONDUCTOR | CL05B224KO5NNNC |  | PWA BOM | In New BOM |
|  |  |  | 62011DF00-023-G | CAP,220nF,+/-10%,X7R,16V,G,SMD0402 | TAIYO ELECTRIC IND.CO.LTD | EMK105B7224KV-FR |  | PWA BOM | In New BOM |
|  | C206,C245 | 2 | 62012P100-015-G | CAP,2.2uF,+/-20%,X7S,10V,G,SMD0402 | MURATA ELEC. NORTH AMERICA | GRM155C71A225M |  | PWA BOM | In Old BOM |
| 42 | C233 | 1 | 62011DF01-015-G | CAP,220nF,+/-10%,X7R,16V,G,SMD0402 | MURATA ELEC. NORTH AMERICA | GRM155R71C224K |  | PWA BOM | In New BOM |
|  |  |  | 62011DF00-026-G | CAP,220nF,+/-10%,X7R,16V,G,SMD0402 | SAMSUNG SEMICONDUCTOR | CL05B224KO5NNNC |  | PWA BOM | In New BOM |
|  |  |  | 62011DF00-023-G | CAP,220nF,+/-10%,X7R,16V,G,SMD0402 | TAIYO ELECTRIC IND.CO.LTD | EMK105B7224KV-FR |  | PWA BOM | In New BOM |
|  | C233 | 1 | 62012NU00-015-G | CAP,1uF,+/-10%,X7R,6.3V,G,SMD0402 | MURATA ELEC. NORTH AMERICA | GRM155R70J105KA12D |  | PWA BOM | In Old BOM |
|  |  |  | 62012NU00-026-G | CAP,1uF,+/-10%,X7R,6.3V,G,SMD0402 | SAMSUNG SEMICONDUCTOR | CL05B105KQ5NQNC |  | PWA BOM | In Old BOM |
| 43 | C137,C141,C143,C145,C148,C150,C185,C186,C188,C847,C851,C852,C853,C854,C857,C858,C866,C902 | 18 | 62011SJ00-026-G | CAP,470nF,+/-10%,X7R,6.3V,G,SMD0402 | SAMSUNG SEMICONDUCTOR | CL05B474KQ5NNNC |  | PWA BOM | In New BOM |
|  |  |  | 62011SJ00-023-G | CAP,470nF,+/-10%,X7R,6.3V,G,SMD0402 | TAIYO ELECTRIC IND.CO.LTD | JMK105B7474KV-F |  | PWA BOM | In New BOM |
|  | C137,C141,C143,C145,C148,C150,C185,C186,C188,C847,C851,C852,C853,C854,C857,C858,C866,C902 | 18 | 62011DF01-015-G | CAP,220nF,+/-10%,X7R,16V,G,SMD0402 | MURATA ELEC. NORTH AMERICA | GRM155R71C224K |  | PWA BOM | In Old BOM |
|  |  |  | 62011DF00-026-G | CAP,220nF,+/-10%,X7R,16V,G,SMD0402 | SAMSUNG SEMICONDUCTOR | CL05B224KO5NNNC |  | PWA BOM | In Old BOM |
|  |  |  | 62011DF00-023-G | CAP,220nF,+/-10%,X7R,16V,G,SMD0402 | TAIYO ELECTRIC IND.CO.LTD | EMK105B7224KV-FR |  | PWA BOM | In Old BOM |
| 44 | C183 | 1 | 62011SJ00-026-G | CAP,470nF,+/-10%,X7R,6.3V,G,SMD0402 | SAMSUNG SEMICONDUCTOR | CL05B474KQ5NNNC |  | PWA BOM | In New BOM |
|  |  |  | 62011SJ00-023-G | CAP,470nF,+/-10%,X7R,6.3V,G,SMD0402 | TAIYO ELECTRIC IND.CO.LTD | JMK105B7474KV-F |  | PWA BOM | In New BOM |
|  | C183 | 1 | 620107G00-015-G | CAP,47nF,+/-10%,X7R,16V,G,SMD0402 | MURATA ELEC. NORTH AMERICA | GRM155R71C473K |  | PWA BOM | In Old BOM |
|  |  |  | 620107G00-023-G | CAP,47nF,+/-10%,X7R,16V,G,SMD0402 | TAIYO ELECTRIC IND.CO.LTD | EMK105B7473KV-F |  | PWA BOM | In Old BOM |
|  |  |  | 620107G00-026-G | CAP,47nF,+/-10%,X7R,16V,G,SMD0402 | SAMSUNG SEMICONDUCTOR | CL05B473KO5NNNC |  | PWA BOM | In Old BOM |
| 45 | C236 | 1 | 62011SJ00-026-G | CAP,470nF,+/-10%,X7R,6.3V,G,SMD0402 | SAMSUNG SEMICONDUCTOR | CL05B474KQ5NNNC |  | PWA BOM | In New BOM |
|  |  |  | 62011SJ00-023-G | CAP,470nF,+/-10%,X7R,6.3V,G,SMD0402 | TAIYO ELECTRIC IND.CO.LTD | JMK105B7474KV-F |  | PWA BOM | In New BOM |
|  | C236 | 1 | 620103700-015-G | CAP,100nF,+/-10%,X7R,10V,G,SMD0402 | MURATA ELEC. NORTH AMERICA | GRM155R71A104K |  | PWA BOM | In Old BOM |
|  |  |  | 620103700-023-G | CAP,100nF,+/-10%,X7R,10V,G,SMD0402 | TAIYO ELECTRIC IND.CO.LTD | LMK105B7104KV-F |  | PWA BOM | In Old BOM |
|  |  |  | 620103700-026-G | CAP,100nF,+/-10%,X7R,10V,G,SMD0402 | SAMSUNG SEMICONDUCTOR | CL05B104KP5NNNC |  | PWA BOM | In Old BOM |
| 46 | C182 | 1 | 62012H100-015-G | CAP,10uF,+/-20%,X6S,10V,G,SMD0603 | MURATA ELEC. NORTH AMERICA | GRM188C81A106M |  | PWA BOM | In New BOM |
|  |  |  | 62012H100-026-G | CAP,10uF,+/-20%,X6S,10V,G,SMD0603 | SAMSUNG SEMICONDUCTOR | CL10X106MP8NRNC |  | PWA BOM | In New BOM |
|  |  |  | 62012H100-023-G | CAP,10uF,+/-20%,X6S,10V,G,SMD0603 | TAIYO ELECTRIC IND.CO.LTD | LMK107BC6106MA-T |  | PWA BOM | In New BOM |
|  | C182 | 1 | 62011DF01-015-G | CAP,220nF,+/-10%,X7R,16V,G,SMD0402 | MURATA ELEC. NORTH AMERICA | GRM155R71C224K |  | PWA BOM | In Old BOM |
|  |  |  | 62011DF00-026-G | CAP,220nF,+/-10%,X7R,16V,G,SMD0402 | SAMSUNG SEMICONDUCTOR | CL05B224KO5NNNC |  | PWA BOM | In Old BOM |
|  |  |  | 62011DF00-023-G | CAP,220nF,+/-10%,X7R,16V,G,SMD0402 | TAIYO ELECTRIC IND.CO.LTD | EMK105B7224KV-FR |  | PWA BOM | In Old BOM |
| 47 | C225,C273 | 2 | 62012H100-015-G | CAP,10uF,+/-20%,X6S,10V,G,SMD0603 | MURATA ELEC. NORTH AMERICA | GRM188C81A106M |  | PWA BOM | In New BOM |
|  |  |  | 62012H100-026-G | CAP,10uF,+/-20%,X6S,10V,G,SMD0603 | SAMSUNG SEMICONDUCTOR | CL10X106MP8NRNC |  | PWA BOM | In New BOM |
|  |  |  | 62012H100-023-G | CAP,10uF,+/-20%,X6S,10V,G,SMD0603 | TAIYO ELECTRIC IND.CO.LTD | LMK107BC6106MA-T |  | PWA BOM | In New BOM |
|  | C225,C273 | 2 | 62012PS00-015-G | CAP,10uF,+/-20%,X6S,4V,G,SMD0402 | MURATA ELEC. NORTH AMERICA | GRM155C80G106M |  | PWA BOM | In Old BOM |
|  |  |  | 62012PS00-023-G | CAP,10uF,+/-20%,X6S,4V,G,SMD0402 | TAIYO ELECTRIC IND.CO.LTD | AMK105CC6106MV-F |  | PWA BOM | In Old BOM |
| 48 | FS22 | 1 | 730102000-086-G | Fuse,Fast acting,24V,10A,G,SMD1206 | LITTELFUSE FAR EAST PTE LTD | 0501010.WR |  | PWA BOM | In New BOM |
|  | FS22 | 1 | 730102000-086-G | Fuse,Fast acting,32V,10A,G,SMD1206 | LITTELFUSE FAR EAST PTE LTD | 0501010.WR |  | PWA BOM | In Old BOM |
| 49 | PBMQ10,PBAQ10,PAMQ10,PAAQ10,PBFQ11,PBEQ11,PAFQ11,PAEQ11 | 8 | 51032DL00-237-G | MOS N,DMT10H014LSS-13,100V,8.9A,15m@10V,G,SO-8,SMD | DIODES INCORPORATION | DMT10H014LSS-13 |  | PWA BOM | In New BOM |
|  | PBMQ10,PBAQ10,PAMQ10,PAAQ10,PBFQ11,PBEQ11,PAFQ11,PAEQ11 | 8 | DMT10H014LSS | MOS N,DMT10H014LSS,100V,7.9A,18m@6V,G,SO8,SMD | DIODES INCORPORATION | DMT10H014LSS |  | PWA BOM | In Old BOM |
| 50 | PBMQ11,PBAQ11,PAMQ11,PAAQ11,PBFQ12,PBEQ12,PAFQ12,PAEQ12 | 8 | 510100W00-237-G | TRANS N,MMBT3904-7-F,40V,0.2A,G,SOT23-3,SMD | DIODES INCORPORATION | MMBT3904-7-F |  | PWA BOM | In New BOM |
|  |  |  | 510101700-185-G | TRANS N,MMBT3904,40V,0.2A,G,SOT23-3,SMD | FAIRCHILD SEMICONDUCTOR CORP | MMBT3904 |  | PWA BOM | In New BOM |
|  | PBMQ11,PBAQ11,PAMQ11,PAAQ11,PBFQ12,PBEQ12,PAFQ12,PAEQ12 | 8 | 510101700-185-G | TRANS N,MMBT3904,40V,0.2A,G,SOT23-3,SMD | FAIRCHILD SEMICONDUCTOR CORP | MMBT3904 |  | PWA BOM | In Old BOM |
| 51 | R1264,R1268,R1272,R1276 | 4 | 610107A00-017-G | RES,0 Ohm,+/-5%,1/16W,G,SMD0402 | KOA SPEER ELECTRONICS, INC. | RK73Z1ETTP |  | PWA BOM | In New BOM |
|  |  |  | 610107A00-024-G | RES,0 Ohm,+/-5%,1/16W,G,SMD0402 | PANASONIC INDUSTRIAL CO.,LTD. | ERJ2GE0R00X |  | PWA BOM | In New BOM |
|  |  |  | 610107A00-029-G | RES,0 Ohm,+/-5%,1/16W,G,SMD0402 | VISHAY ENTER TECHNO LOGY.INC | CRCW04020000Z0ED |  | PWA BOM | In New BOM |
|  | R1264,R1268,R1272,R1276 | 4 | 61100LV00-017-G | RES,10KOhm,+/-1%,1/16W,G,SMD0402 | KOA SPEER ELECTRONICS, INC. | RN731ETTP1002F50 |  | PWA BOM | In Old BOM |
| 52 | PBAR57,PAAR57 | 2 | 61100QV00-017-G | RES,49.9 Ohm,+/-0.5%,1/16W,G,SMD0402 | KOA SPEER ELECTRONICS, INC. | RN731ETTP49R9D50 |  | PWA BOM | In New BOM |
|  | PBAR57,PAAR57 | 2 | 61100QG00-017-G | RES,649 Ohm,+/-0.1%,1/16W,G,SMD0402 | KOA SPEER ELECTRONICS, INC. | RN731ETTP6490B25 |  | PWA BOM | In Old BOM |
|  |  |  | 61100QG00-024-G | RES,649 Ohm,+/-0.1%,1/16W,G,SMD0402 | PANASONIC INDUSTRIAL CO.,LTD. | ERA2AEB6490X |  | PWA BOM | In Old BOM |
|  |  |  | 61100QG00-029-G | RES,649 Ohm,+/-0.1%,1/16W,G,SMD0402 | VISHAY ENTER TECHNO LOGY.INC | TNPW0402649RBEED |  | PWA BOM | In Old BOM |
| 53 | PBMR26,PAMR26 | 2 | 611003200-017-G | RES,10KOhm,+/-0.1%,1/16W,G,SMD0402 | KOA SPEER ELECTRONICS, INC. | RN731ETTP1002B25 |  | PWA BOM | In New BOM |
|  | PBMR26,PAMR26 | 2 | 61100RN00-017-G | RES,15.4KOhm,+/-0.1%,1/16W,G,SMD0402 | KOA SPEER ELECTRONICS, INC. | RN731ETTP1542B25 |  | PWA BOM | In Old BOM |
| 54 | PBMU1,PBFU1,PBEU1,PBAU1,PAMU1,PAFU1,PAEU1,PAAU1 | 8 | ISL68137IRAZ-EVT3 | IC,PWM Controller,ISL68137IRAZ-T,G,QFN-48,SMD | INTERSIL CORPORATION | ISL68137IRAZ-EVT3 |  | PWA BOM | In New BOM |
|  | PBMU1,PBFU1,PBEU1,PBAU1,PAMU1,PAFU1,PAEU1,PAAU1 | 8 | 320242200-230-G | IC,PWM Controller,ISL68137IRAZ-T,G,QFN-48,SMD | INTERSIL CORPORATION | ISL68137IRAZ-T |  | PWA BOM | In Old BOM |
| 55 | PBFR513,PBER513,PAFR513,PAER513 | 4 | 61015NJ00-017-G | RES,6.04 Ohm,+/-1%,1/4W,G,SMD1206 | KOA SPEER ELECTRONICS, INC. | RK73H2BTTD6R04F |  | PWA BOM | In New BOM |
|  | PBFR513,PBER513,PAFR513,PAER513 | 4 | 61013A200-017-G | RES,6.8 Ohm,+/-1%,1/4W,G,SMD1206 | KOA SPEER ELECTRONICS, INC. | RK73H2BTTD6R80F |  | PWA BOM | In Old BOM |
|  |  |  | 61013A200-029-G | RES,6.8 Ohm,+/-1%,1/4W,G,SMD1206 | VISHAY | CRCW12066R80FKEA |  | PWA BOM | In Old BOM |
| 56 | PBMR57,PAMR57 | 2 | 61011GE00-017-G | RES,21 Ohm,+/-1%,1/16W,G,SMD0402 | KOA SPEER ELECTRONICS, INC. | RK73H1ETTP21R0F |  | PWA BOM | In New BOM |
|  | PBMR57,PAMR57 | 2 | 61012C600-017-G | RES,12.4 Ohm,+/-1%,1/16W,G,SMD0402 | KOA SPEER ELECTRONICS, INC. | RK73H1ETTP12R4F |  | PWA BOM | In Old BOM |
| 57 | PAMR66,PBMR69,PBMR76,PAMR76 | 4 | 61010R900-017-G | RES,27.4KOhm,+/-1%,1/10W,G,SMD0603 | KOA SPEER ELECTRONICS, INC. | RK73H1JTTD2742F |  | PWA BOM | In New BOM |
|  | PAMR66,PBMR69,PBMR76,PAMR76 | 4 | 610107K00-017-G | RES,24.9KOhm,+/-1%,1/10W,G,SMD0603 | KOA SPEER ELECTRONICS, INC. | RK73H1JTTD2492F |  | PWA BOM | In Old BOM |
| 58 | PBNR11 | 1 | 610114B00-017-G | RES,2.49KOhm,+/-1%,1/16W,G,SMD0402 | KOA SPEER ELECTRONICS, INC. | RK73H1ETTP2491F |  | PWA BOM | In New BOM |
|  |  |  | 610114B00-024-G | RES,2.49KOhm,+/-1%,1/16W,G,SMD0402 | PANASONIC | ERJ2RKF2491X |  | PWA BOM | In New BOM |
|  |  |  | 610114B00-029-G | RES,2.49KOhm,+/-1%,1/16W,G,SMD0402 | VISHAY | CRCW04022K49FKED |  | PWA BOM | In New BOM |
|  | PBNR11 | 1 | 610112800-017-G | RES,6.04KOhm,+/-1%,1/16W,G,SMD0402 | KOA SPEER ELECTRONICS, INC. | RK73H1ETTP6041F |  | PWA BOM | In Old BOM |
|  |  |  | 610112800-029-G | RES,6.04KOhm,+/-1%,1/16W,G,SMD0402 | VISHAY ENTER TECHNO LOGY.INC | CRCW04026K04FKED |  | PWA BOM | In Old BOM |
| 59 | PBNR14 | 1 | 61011CJ00-017-G | RES,365 Ohm,+/-1%,1/16W,G,SMD0402 | KOA SPEER ELECTRONICS, INC. | RK73H1ETTP3650F |  | PWA BOM | In New BOM |
|  |  |  | 61011CJ00-024-G | RES,365 Ohm,+/-1%,1/16W,G,SMD0402 | PANASONIC | ERJ2RKF3650X |  | PWA BOM | In New BOM |
|  |  |  | 61011CJ00-029-G | RES,365 Ohm,+/-1%,1/16W,G,SMD0402 | VISHAY | CRCW0402365RFKEDC |  | PWA BOM | In New BOM |
|  | PBNR14 | 1 | 61010FF00-017-G | RES,150 Ohm,+/-1%,1/16W,G,SMD0402 | KOA SPEER ELECTRONICS, INC. | RK73H1ETTP1500F |  | PWA BOM | In Old BOM |
|  |  |  | 61010FF00-024-G | RES,150 Ohm,+/-1%,1/16W,G,SMD0402 | PANASONIC INDUSTRIAL CO.,LTD. | ERJ2RKF1500X |  | PWA BOM | In Old BOM |
| 60 | PETC7 | 1 | 62011AM00-015-G | CAP,6.8nF,+/-10%,X7R,50V,G,SMD0402 | MURATA ELEC. NORTH AMERICA | GRM155R71H682K |  | PWA BOM | In New BOM |
|  | PETC7 | 1 | 620109700-015-G | CAP,3.3nF,+/-10%,X7R,50V,G,SMD0402 | MURATA ELEC. NORTH AMERICA | GRM155R71H332K |  | PWA BOM | In Old BOM |
|  |  |  | 620109700-026-G | CAP,3.3nF,+/-10%,X7R,50V,G,SMD0402 | SAMSUNG SEMICONDUCTOR | CL05B332KB5NNNC |  | PWA BOM | In Old BOM |
|  |  |  | 620109700-023-G | CAP,3.3nF,+/-10%,X7R,50V,G,SMD0402 | TAIYO ELECTRIC IND.CO.LTD | UMK105B7332KV-F |  | PWA BOM | In Old BOM |
| 61 | Q2,Q6 | 2 | 51030CQ00-185-G | MOS N,2N7002,60V,115mA,7.5ohm@5V,G,SOT23-3,SMD | FAIRCHILD SEMICONDUCTOR CORP | 2N7002 |  | PWA BOM | In New BOM |
|  |  |  | 510301N00-223-G | MOS N,2N7002LT1G,60V,0.115A,7.5ohm@5V,G,SOT23-3,SMD | ON SEMICONDUCTOR CORP | 2N7002LT1G |  | PWA BOM | In New BOM |
|  | Q2,Q6 | 2 | 510301N00-223-G | MOS N,2N7002LT1G,60V,0.115A,7.5ohm@5V,G,SOT23-3,SMD | ON SEMICONDUCTOR CORP | 2N7002LT1G |  | PWA BOM | In Old BOM |
| 62 | J105,J106,J107,J108,J109,J110,J111,J112,J113,J114,J115,J116,J118,J119,J120,J121,J122,J123,J124,J126,J127,J128,J129,J130,J131,J132,J133,J134,J135,J136,J137,J138,J139,J140,J141,J149 | 36 | 3406AUA00-309-G | CONN,Pin Header,1X2,V/T,Bla,2.54mm,10u,G,SMD-2 | SAMTEC INC. | ASP-195607-01 |  | PWA BOM | In New BOM |
|  | J105,J106,J107,J108,J109,J110,J111,J112,J113,J114,J115,J116,J118,J119,J120,J121,J122,J123,J124,J126,J127,J128,J129,J130,J131,J132,J133,J134,J135,J136,J137,J138,J139,J140,J141,J149 | 36 | ASP-195607-01 | CONN,Pin Header,1X2,V/T,Bla,2.54mm,10u,G,SMD-2 | SAMTEC INC. | ASP-195607-01 |  | PWA BOM | In Old BOM |
| 63 | J148 | 1 | 340672300-317-G | CONN,Pin Header,1X4,V/T,Bla,2.54mm,30u,G,SMD-4 | MOLEX INCORPORATED | 87898-0455 |  | PWA BOM | In New BOM |
|  | J148 | 1 | 340670200-317-G | CONN,Pin Header,1X4,V/T,Bla,2.54mm,30u,G,SMD-4 | MOLEX INCORPORATED | 87898-0425 |  | PWA BOM | In Old BOM |
| 64 | PBFU3,PBEU3,PAMU3,PAFU3,PAEU3,PBMU3 | 6 | PI3755-02-LGIZ | IC,Regulator,PI3755-02-LGIZ,ADJ,4A,G,LGA-71,SMD | Vicor Corporation | PI3755-02-LGIZ |  | PWA BOM | In New BOM |
|  | PBFU3,PBEU3,PAMU3,PAFU3,PAEU3,PBMU3 | 6 | 320148D00-53N-G | IC,Regulator,PI3755-01-LGIZ,ADJ,4A,G,LGA-71,SMD | Vicor Corporation | PI3755-01-LGIZ |  | PWA BOM | In Old BOM |
| 65 | PAMU4,PBMU4 | 2 | 880302800-53N-G | Converter,input 0V~60V,131W,G,VTM48MP010C105AG0 | Vicor Corporation | VTM48MP010C105AG0 |  | PWA BOM | In New BOM |
|  | PAMU4,PBMU4 | 2 | 880302600-53N-G | Converter,input 0V~52V,120W,G,VTM48RP015C076AG0 | Vicor Corporation | VTM48RP015C076AG0 |  | PWA BOM | In Old BOM |
| 66 | J_UART_LOM1 | 1 | 3406AQH00-317-G | CONN,Header,Pin Header,1X6,V/T,Bla,2.54mm,G,SMD-6 | MOLEX INCORPORATED | 87898-0656 |  | DEPOP_GA | In New BOM |
|  | J_UART_LOM1 | 1 | 3406AQH00-317-G | CONN,Pin Header,1X6,V/T,Bla,2.54mm,15u,G,DIP-6 | MOLEX | 87898-0656 |  | DEPOP_GA | In Old BOM |
| ##### Change Revision |  |  |  |  |  |  |  |  |  |
| Sheet | REV OF BOM | CUSTOMER | CUSTOMER P/N | PWA PN | PWA DESCRIPTION | PWA REV | DATE | Remark |  |
| PWA BOM | X14 | Google |  |  |  |  |  | In New BOM |  |
| PWA BOM | X13 | Google |  |  |  |  |  | In Old BOM |  |
| OOOOOOOOOOOOOOOOOOOOOOOOOOOOOOOOOOOOOOOOOOOOOOOOOOOOOOOOOOOOOOOOOOOOOOOOOOOOOOOOOOOOOOOOOO | OOOOOOOOOOOOOOOOOOOOOOOOOOOOOOOOOOOOOOOOOOOOOOOOOOOOOOOOOOOOOOOOOOOOOOOOOOOOOOOOOOOOOOOOOO | OOOOOOOOOOOOOOOOOOOOOOOOOOOOOOOOOOOOOOOOOOOOOOOOOOOOOOOOOOOOOOOOOOOOOOOOOOOOOOOOOOOOOOOOOO | OOOOOOOOOOOOOOOOOOOOOOOOOOOOOOOOOOOOOOOOOOOOOOOOOOOOOOOOOOOOOOOOOOOOOOOOOOOOOOOOOOOOOOOOOO | OOOOOOOOOOOOOOOOOOOOOOOOOOOOOOOOOOOOOOOOOOOOOOOOOOOOOOOOOOOOOOOOOOOOOOOOOOOOOOOOOOOOOOOOOO | OOOOOOOOOOOOOOOOOOOOOOOOOOOOOOOOOOOOOOOOOOOOOOOOOOOOOOOOOOOOOOOOOOOOOOOOOOOOOOOOOOOOOOOOOO | OOOOOOOOOOOOOOOOOOOOOOOOOOOOOOOOOOOOOOOOOOOOOOOOOOOOOOOOOOOOOOOOOOOOOOOOOOOOOOOOOOOOOOOOOO | OOOOOOOOOOOOOOOOOOOOOOOOOOOOOOOOOOOOOOOOOOOOOOOOOOOOOOOOOOOOOOOOOOOOOOOOOOOOOOOOOOOOOOOOOO | OOOOOOOOOOOOOOOOOOOOOOOOOOOOOOOOOOOOOOOOOOOOOOOOOOOOOOOOOOOOOOOOOOOOOOOOOOOOOOOOOOOOOOOOOO | OOOOOOOOOOOOOOOOOOOOOOOOOOOOOOOOOOOOOOOOOOOOOOOOOOOOOOOOOOOOOOOOOOOOOOOOOOOOOOOOOOOOOOOOOO |
| Second Source Change |  |  |  |  |  |  |  |  |  |
| Item | Location | Change Type | Foxconn P/N | Part Description | Manufacturer Full Name | Manufacturer P/N | RoHS | Sheet |  |
| 1 | C1458,C1463,C1486,C1489,C1492,C1774,C1775,C1793,C1795,C1839,C1840,C1883,C1885,C1938,C1939,C1950,C1976 |  | 620115801-015-G | CAP,22uF,+/-10%,X7R,10V,G,SMD1206 | MURATA ELEC. NORTH AMERICA | GRM31CR71A226KE15L |  | PWA BOM |  |
|  |  | NO | 620115800-023-G | CAP,22uF,+/-10%,X7R,10V,G,SMD1206 | TAIYO ELECTRIC IND.CO.LTD | LMK316B7226KL-TR |  | PWA BOM |  |
|  |  | ADD | 620115800-026-G | CAP,22uF,+/-10%,X7R,10V,G,SMD1206 | SAMSUNG | CL31B226KPHNNNE |  | PWA BOM |  |
| 2 | C1542 |  | 62010GW00-015-G | CAP,10pF,+/-5%,NPO,50V,G,SMD0402 | MURATA ELEC. NORTH AMERICA | GRM1555C1H100J |  | PWA BOM |  |
|  |  | ADD | 620102D00-026-G | CAP,10pF,+/-5%,NPO,50V,G,SMD0402 | SAMSUNG | CL05C100JB5NNNC |  | PWA BOM |  |
| 3 | PBNC1,PANC8,PQPC16,C2013,C2015,C2017,C2019,PSRC3008 |  | 620130V00-015-G | CAP,10uF,+/-20%,X6S,16V,G,SMD0603 | MURATA ELEC. NORTH AMERICA | GRM188C81C106MA73D |  | PWA BOM |  |
|  |  | NO | 620130V00-023-G | CAP,10uF,+/-20%,X6S,16V,G,SMD0603 | TAIYO ELECTRIC IND.CO.LTD | EMK107BC6106MA-T |  | PWA BOM |  |
|  |  | ADD | 620130V00-026-G | CAP,10uF,+/-20%,X6S,16V,G,SMD0603 | SAMSUNG | CL10X106MO8NRNC |  | PWA BOM |  |
| 4 | PBFC28,PBEC28,PAFC28,PAEC28,PBMC29,PBFC29,PBEC29,PBAC29,PAMC29,PAFC29,PAEC29,PAAC29,PBMC30,PBFC30,PBEC30,PBAC30,PAMC30,PAFC30,PAEC30,PAAC30,PBMC31,PBFC31,PBEC31,PBAC31,PAMC31,PAFC31,PAEC31,PAAC31,PBMC32,PBFC32,PBEC32,PBAC32,PAMC32,PAFC32,PAEC32,PAAC32,PBMC33,PBFC33,PBEC33,PBAC33,PAMC33,PAFC33,PAEC33,PAAC33,PBMC34,PBFC34,PBEC34,PBAC34,PAMC34,PAFC34,PAEC34,PAAC34,PBMC35,PBFC35,PBEC35,PBAC35,PAMC35,PAFC35,PAEC35,PAAC35,PBMC36,PBFC36,PBEC36,PBAC36,PAMC36,PAFC36,PAEC36,PAAC36,PBMC37,PBFC37,PBEC37,PBAC37,PAMC37,PAFC37,PAEC37,PAAC37,PBMC38,PBFC38,PBEC38,PBAC38,PAMC38,PAFC38,PAEC38,PAAC38,PBMC39,PBFC39,PBEC39,PBAC39,PAMC39,PAFC39,PAEC39,PAAC39,PBMC40,PBFC40,PBEC40,PBAC40,PAMC40,PAFC40,PAEC40,PAAC40,PBMC41,PBFC41,PBEC41,PBAC41,PAMC41,PAFC41,PAEC41,PAAC41,PBMC42,PBFC42,PBEC42,PBAC42,PAMC42,PAFC42,PAEC42,PAAC42,PBMC43,PBFC43,PBEC43,PBAC43,PAMC43,PAFC43,PAEC43,PAAC43,PBMC44,PBFC44,PBEC44,PBAC44,PAMC44,PAFC44,PAEC44,PAAC44,PBMC45,PBFC45,PBEC45,PBAC45,PAMC45,PAFC45,PAEC45,PAAC45,PBMC46,PBFC46,PBEC46,PBAC46,PAMC46,PAFC46,PAEC46,PAAC46,PBMC47,PBFC47,PBEC47,PBAC47,PAMC47,PAFC47,PAEC47,PAAC47,PBMC48,PBFC48,PBEC48,PBAC48,PAMC48,PAFC48,PAEC48,PAAC48,PBMC49,PBFC49,PBEC49,PBAC49,PAMC49,PAFC49,PAEC49,PAAC49,PBMC50,PBFC50,PBEC50,PBAC50,PAMC50,PAFC50,PAEC50,PAAC50,PBMC51,PBFC51,PBEC51,PBAC51,PAMC51,PAFC51,PAEC51,PAAC51,PBMC52,PBFC52,PBEC52,PBAC52,PAMC52,PAFC52,PAEC52,PAAC52,PBMC53,PBFC53,PBEC53,PBAC53,PAMC53,PAFC53,PAEC53,PAAC53,PBMC54,PBFC54,PBEC54,PBAC54,PAMC54,PAFC54,PAEC54,PAAC54,PBMC55,PBFC55,PBEC55,PBAC55,PAMC55,PAFC55,PAEC55,PAAC55,PBMC56,PBFC56,PBEC56,PBAC56,PAMC56,PAFC56,PAEC56,PAAC56,PBMC57,PBFC57,PBEC57,PBAC57,PAMC57,PAFC57,PAEC57,PAAC57,PBMC58,PBAC58,PAMC58,PAAC58,PBAC59,PAAC59,PBAC60,PAAC60,PBAC61,PAAC61,PBFC62,PBEC62,PBAC62,PAFC62,PAEC62,PAAC62,PBMC63,PBFC63,PBEC63,PBAC63,PAMC63,PAFC63,PAEC63,PAAC63,PBMC64,PBFC64,PBEC64,PBAC64,PAMC64,PAFC64,PAEC64,PAAC64,PBMC65,PBFC65,PBEC65,PBAC65,PAMC65,PAFC65,PAEC65,PAAC65,PBMC66,PBFC66,PBEC66,PBAC66,PAMC66,PAFC66,PAEC66,PAAC66,PBMC67,PBFC67,PBEC67,PBAC67,PAMC67,PAFC67,PAEC67,PAAC67,PBMC68,PBFC68,PBEC68,PBAC68,PAMC68,PAFC68,PAEC68,PAAC68,PBMC69,PBFC69,PBEC69,PBAC69,PAMC69,PAFC69,PAEC69,PAAC69,PBMC70,PBFC70,PBEC70,PBAC70,PAMC70,PAFC70,PAEC70,PAAC70,PBMC71,PBFC71,PBEC71,PBAC71,PAMC71,PAFC71,PAEC71,PAAC71,PBMC72,PBAC72,PAMC72,PAAC72,PBAC73,PAAC73,PBAC74,PAAC74,PBAC75,PAAC75,PBAC76,PAAC76,PBAC77,PAAC77,PBAC78,PAAC78,PBAC81,PAAC81,PBAC82,PAAC82,PBAC83,PAAC83,PBAC84,PAAC84,PBAC85,PAAC85,PBAC86,PAAC86,PBAC87,PAAC87,PBAC88,PAAC88,PBAC89,PAAC89,PBAC90,PAAC90,PBAC91,PAAC91,PBAC92,PAAC92,PBAC93,PAAC93,PBAC94,PAAC94,PBAC95,PAAC95,PBAC96,PAAC96,PBAC97,PAAC97,PBAC98,PAAC98,PBAC99,PAAC99,PBAC100,PAAC100,PBAC101,PAAC101,PBAC102,PAAC102,PBAC103,PAAC103,PBAC104,PAAC104,PBAC105,PAAC105,PBAC106,PAAC106,PBAC107,PAAC107,PBAC108,PAAC108,PBAC109,PAAC109,PBAC110,PAAC110,PBAC113,PAAC113,PBAC114,PAAC114,PBAC115,PAAC115,PBAC116,PAAC116,PBAC117,PAAC117,PBAC118,PAAC118,PBAC119,PAAC119,PBAC120,PAAC120,PBAC121,PAAC121,PBAC122,PAAC122,PBAC127,PAAC127,PBAC128,PAAC128,PBAC129,PAAC129,PBAC130,PAAC130,PBAC131,PAAC131,PBAC132,PAAC132,PBAC133,PAAC133,PBAC134,PAAC134,PBAC135,PAAC135,PBAC136,PAAC136,PBAC137,PAAC137,PBAC138,PAAC138,PBAC139,PAAC139,PBAC140,PAAC140,PBAC141,PAAC141,PBAC142,PAAC142,PBAC143,PAAC143,PBAC144,PAAC144,PBAC145,PAAC145,PBAC146,PAAC146,PBAC147,PAAC147,PBAC148,PAAC148,PBAC149,PAAC149,PBAC150,PAAC150,PBAC151,PAAC151,PBAC152,PAAC152,PBAC153,PAAC153,PBAC154,PAAC154,PBAC155,PAAC155,PBAC156,PAAC156,PBFC501,PBEC501,PAFC501,PAEC501,C2168,C2169,C2170,C2172,C2173,C2174,C2175,C2176,C2177,C2178,C2179 |  | 62012PS00-015-G | CAP,10uF,+/-20%,X6S,4V,G,SMD0402 | MURATA ELEC. NORTH AMERICA | GRM155C80G106M |  | PWA BOM |  |
|  |  | NO | 62012PS00-023-G | CAP,10uF,+/-20%,X6S,4V,G,SMD0402 | TAIYO ELECTRIC IND.CO.LTD | AMK105CC6106MV-F |  | PWA BOM |  |
|  |  | ADD | 62012PS00-026-G | CAP,10uF,+/-20%,X6S,4V,G,SMD0402 | SAMSUNG | CL05X106MR5NUNC |  | PWA BOM |  |
| 5 | PBMC1,PBFC1,PBEC1,PBAC1,PAMC1,PAFC1,PAEC1,PAAC1,PBMC2,PBFC2,PBEC2,PBAC2,PAMC2,PAFC2,PAEC2,PAAC2,PBMC22,PBFC22,PBEC22,PBAC22,PAMC22,PAFC22,PAEC22,PAAC22,PBMC450,PBFC450,PBEC450,PBAC450,PAMC450,PAFC450,PAEC450,PAAC450,PBAC452,PAAC452 |  | 62012RJ00-015-G | CAP,4.7uF,+/-10%,X6S,16V,G,SMD0603 | MURATA ELEC. NORTH AMERICA | GRM188C81C475K |  | PWA BOM |  |
|  |  | NO | 62012RJ00-023-G | CAP,4.7uF,+/-10%,X6S,16V,G,SMD0603 | TAIYO ELECTRIC IND.CO.LTD | EMK107BC6475KA-T |  | PWA BOM |  |
|  |  | ADD | 62012RJ02-026-G | CAP,4.7uF,+/-10%,X6S,16V,G,SMD0603 | SAMSUNG | CL10X475KO8NRNC |  | PWA BOM |  |
| 6 | PBFC59,PBEC59,PAFC59,PAEC59,PBMC60,PAMC60,PBAC124,PAAC124 |  | 62010WW01-015-G | CAP,1.8nF,+/-10%,X7R,50V,G,SMD0402 | MURATA ELEC. NORTH AMERICA | GRM155R71H182KA01D |  | PWA BOM |  |
|  |  | ADD | 62010WW00-026-G | CAP,1.8nF,+/-10%,X7R,50V,G,SMD0402 | SAMSUNG | CL05B182KB5NNNC |  | PWA BOM |  |
| 7 | PBMQ11,PBAQ11,PAMQ11,PAAQ11,PBFQ12,PBEQ12,PAFQ12,PAEQ12,Q8,PHAQ8,Q85,Q86,Q87,Q88,Q89,Q90,Q91,Q92 |  | 510100W00-237-G | TRANS N,MMBT3904-7-F,40V,0.2A,G,SOT23-3,SMD | DIODES INCORPORATION | MMBT3904-7-F |  | PWA BOM |  |
|  |  | ADD | 510101700-185-G | TRANS N,MMBT3904,40V,0.2A,G,SOT23-3,SMD | FAIRCHILD SEMICONDUCTOR CORP | MMBT3904 |  | PWA BOM |  |
| 8 | PBER7,PAMR7,PAMR8,PAFR9,PAFR10,PAER10,PBAR11,PAER11,PBFR12,PBAR12,PAAR12,PBMR13,PBFR13,PBER14,PAAR14,PBMR15,PBMR17,PBFR17,PBER17,PBAR17,PAMR17,PAFR17,PAER17,PAAR17,PBMR21,PBFR21,PBER21,PBAR21,PAMR21,PAFR21,PAER21,PAAR21,PBMR24,PBFR24,PBER24,PBAR24,PAMR24,PAFR24,PAER24,PAAR24,PBMR27,PBFR27,PBER27,PBAR27,PAMR27,PAFR27,PAER27,PAAR27 |  | 61010PS00-017-G | RES,200KOhm,+/-1%,1/16W,G,SMD0402 | KOA SPEER ELECTRONICS, INC. | RK73H1ETTP2003F |  | PWA BOM |  |
|  |  | ADD | 61010PS00-029-G | RES,200KOhm,+/-1%,1/16W,G,SMD0402 | VISHAY | CRCW0402200KFKED |  | PWA BOM |  |
| 9 | PBAR26,PAAR26 |  | 61100YD00-017-G | RES,9.53KOhm,+/-0.1%,1/16W,G,SMD0402 | KOA SPEER ELECTRONICS, INC. | RN731ETTP9531B25 |  | PWA BOM |  |
|  |  | ADD | 61100YD00-024-G | RES,9.53KOhm,+/-0.1%,1/16W,G,SMD0402 | PANASONIC | ERA2AEB9531X |  | PWA BOM |  |
| 10 | PBMR107,PAMR107,PBER109,PAFR109,PAER109,PBFR110,PBAR113,PAAR113 |  | 61011B300-017-G | RES,1MOhm,+/-1%,1/16W,G,SMD0402 | KOA SPEER ELECTRONICS, INC. | RK73H1ETTP1004F |  | PWA BOM |  |
|  |  | ADD | 61011B300-029-G | RES,1MOhm,+/-1%,1/16W,G,SMD0402 | VISHAY | CRCW04021M00FKED |  | PWA BOM |  |
| 11 | PBMR109,PAMR109,PBER111,PAFR111,PAER111,PBFR112,PBAR115,PAAR115 |  | 61011GU00-017-G | RES,274 Ohm,+/-1%,1/16W,G,SMD0402 | KOA SPEER ELECTRONICS, INC. | RK73H1ETTP2740F |  | PWA BOM |  |
|  |  | ADD | 61011GU00-029-G | RES,274 Ohm,+/-1%,1/16W,G,SMD0402 | VISHAY | CRCW0402274RFKED |  | PWA BOM |  |
| 12 | PBMR117,PAMR117,PBER119,PAFR119,PAER119,PBFR120,PBAR123,PAAR123 |  | 610114P00-017-G | RES,715 Ohm,+/-1%,1/16W,G,SMD0402 | KOA SPEER ELECTRONICS, INC. | RK73H1ETTP7150F |  | PWA BOM |  |
|  |  | ADD | 610114P00-024-G | RES,715 Ohm,+/-1%,1/16W,G,SMD0402 | PANASONIC | ERJ2RKF7150X |  | PWA BOM |  |
| 13 | PHAR79,PBMR118,PAMR118,PBER120,PAFR120,PAER120,PBFR121,PBAR124,PAAR124 |  | 61011L200-017-G | RES,3.65KOhm,+/-1%,1/16W,G,SMD0402 | KOA SPEER ELECTRONICS, INC. | RK73H1ETTP3651F |  | PWA BOM |  |
|  |  | ADD | 61011L200-029-G | RES,3.65KOhm,+/-1%,1/16W,G,SMD0402 | VISHAY | 61011L200-029-G |  | PWA BOM |  |
| 14 | PBMR304,PBAR304,PAMR304,PAAR304 |  | 61011BH00-017-G | RES,22.1 Ohm,+/-1%,1/16W,G,SMD0402 | KOA SPEER ELECTRONICS, INC. | RK73H1ETTP22R1F |  | PWA BOM |  |
|  |  | ADD | 61011BH00-024-G | RES,22.1 Ohm,+/-1%,1/16W,G,SMD0402 | PANASONIC | ERJ2RKF22R1X |  | PWA BOM |  |
|  |  | ADD | 61011BH00-029-G | RES,22.1 Ohm,+/-1%,1/16W,G,SMD0402 | VISHAY | CRCW040222R1FKED |  | PWA BOM |  |
| 15 | PBMR3,PAMR12 |  | 61011QD00-017-G | RES,330 Ohm,+/-1%,1/16W,G,SMD0402 | KOA SPEER ELECTRONICS, INC. | RK73H1ETTP3300F |  | PWA BOM |  |
|  |  | ADD | 61011QD00-029-G | RES,330 Ohm,+/-1%,1/16W,G,SMD0402 | VISHAY | CRCW0402330RFKED |  | PWA BOM |  |
| 16 | PBNR17,PANR17 |  | 61011B600-017-G | RES,5.36KOhm,+/-1%,1/16W,G,SMD0402 | KOA SPEER ELECTRONICS, INC. | RK73H1ETTP5361F |  | PWA BOM |  |
|  |  | ADD | 61011B600-024-G | RES,5.36KOhm,+/-1%,1/16W,G,SMD0402 | PANASONIC | ERJ2RKF5361X |  | PWA BOM |  |
|  |  | ADD | 61011B600-029-G | RES,5.36KOhm,+/-1%,1/16W,G,SMD0402 | VISHAY | CRCW04025K36FKEDC |  | PWA BOM |  |
| 17 | PSRR20,PBNR23,PANR23,PHAR28,PHAR29,PHAR30,R668,R669,R683,R762,R763,R764,R765,R766,R767,R769,R770,R772,R773,R774,R775,R776,R777,R778,R779,R780,R781,R782,R783,R784,R786,R787,R788,R791,R795,R800,R801,R804,R805,R806,R807,R808,R809,R811,R814,R817,R820,R822,R823,R825,R827,R828,R830,R893,R894,R901,R902,R922,R942,R943,R944,R945,R949,R950,R955,R956,R957,R958,R959,R1129,R1135,R1138,R1148,R1149,R1150,R1151,R1152,R1156,R1159,R1162,R1164,R1165,R1172,R1174,R1175,R1176,R1184,R1185,R1186,R1190,R1195,R1197,R1198,R1199,R1210,R1211,R1212,R1213,R1218,R1219,R1220,R1221,R1222,R1223,R1224,R1240,R1256,R1257,R1263,R1267,R1271,R1275,R1295,R1296,R1460,R1461,R1462,R1463,R1464,R1465,R1466,R1467,R1468,R1469,R1470,R1471,R1474,R1475,R1476,R1477,R1495,R1504,R1507,R1508,R1509,R1511,R1512,R1515,R1520,R1521,R1589,R1590,R1592,R1593,R1603,R1604,R1605,R1606,R1779,R1780,R1781,R1782,R1786,R1789,R1801,R1820,R1821,R1834 |  | 61010LA00-017-G | RES,4.7KOhm,+/-1%,1/16W,G,SMD0402 | KOA SPEER ELECTRONICS, INC. | RK73H1ETTP4701F |  | PWA BOM |  |
|  |  | ADD | 61010LA00-029-G | RES,4.7KOhm,+/-1%,1/16W,G,SMD0402 | VISHAY | CRCW04024K70FKED |  | PWA BOM |  |
| 18 | PANR26 |  | 61011BS00-017-G | RES,2.05KOhm,+/-1%,1/16W,G,SMD0402 | KOA SPEER ELECTRONICS, INC. | RK73H1ETTP2051F |  | PWA BOM |  |
|  |  | ADD | 61011BS00-029-G | RES,2.05KOhm,+/-1%,1/16W,G,SMD0402 | VISHAY | CRCW04022K05FKED |  | PWA BOM |  |
| 19 | PBNR26 |  | 610118R00-017-G | RES,1.54KOhm,+/-1%,1/16W,G,SMD0402 | KOA SPEER ELECTRONICS, INC. | RK73H1ETTP1541F |  | PWA BOM |  |
|  |  | ADD | 610118R00-029-G | RES,1.54KOhm,+/-1%,1/16W,G,SMD0402 | VISHAY | CRCW04021K54FKED |  | PWA BOM |  |
| 20 | PUAR2,PSAR2,PRAR2,PQAR2,PPAR2,PIAR2,PFAR2,PEAR2 |  | 610114200-017-G | RES,10.7KOhm,+/-1%,1/16W,G,SMD0402 | KOA SPEER ELECTRONICS, INC. | RK73H1ETTP1072F |  | PWA BOM |  |
|  |  | ADD | 610114200-024-G | RES,10.7KOhm,+/-1%,1/16W,G,SMD0402 | PANASONIC | ERJ2RKF1072X |  | PWA BOM |  |
|  |  | ADD | 610114200-029-G | RES,10.7KOhm,+/-1%,1/16W,G,SMD0402 | VISHAY | CRCW040210K7FKED |  | PWA BOM |  |
| 21 | PUAR4,PSAR4,PRAR4,PQAR4,PPAR4,PIAR4,PFAR4,PEAR4,PUAR6,PSAR6,PRAR6,PQAR6,PPAR6,PIAR6,PFAR6,PEAR6 |  | 611004D00-017-G | RES,1.5KOhm,+/-0.1%,1/16W,G,SMD0402 | KOA SPEER ELECTRONICS, INC. | RN731ETTP1501B25 |  | PWA BOM |  |
|  |  | ADD | 611004D00-029-G | RES,1.5KOhm,+/-0.1%,1/16W,G,SMD0402 | VISHAY | TNPW04021K50BEED |  | PWA BOM |  |
| 22 | PUAR10,PSAR10,PRAR10,PQAR10,PPAR10,PIAR10,PFAR10,PEAR10 |  | 610128200-017-G | RES,26.1 Ohm,+/-1%,1/16W,G,SMD0402 | KOA SPEER ELECTRONICS, INC. | RK73H1ETTP26R1F |  | PWA BOM |  |
|  |  | ADD | 610128200-029-G | RES,26.1 Ohm,+/-1%,1/16W,G,SMD0402 | VISHAY | CRCW040226R1FKED |  | PWA BOM |  |
| 23 | PSLC16,PSFC16,PSEC16,PSDC16,PEEC16,PEDC16 |  | 62012CM01-015-G | CAP,10uF,+/-20%,X6S,4V,G,SMD0603 | MURATA ELEC. NORTH AMERICA | GRM188C80G106M |  | PWA BOM |  |
|  |  | ADD | 62012CM00-026-G | CAP,10uF,+/-20%,X6S,4V,G,SMD0603 | SAMSUNG | CL10X106MR8NNNC |  | PWA BOM |  |
| 24 | PSLR17,PSFR17,PSER17,PSDR17,PQPR17,PFRR17,PEER17,PEDR17,PEDR19 |  | 611004M00-017-G | RES,16.5KOhm,+/-0.1%,1/16W,G,SMD0402 | KOA SPEER ELECTRONICS, INC. | RN731ETTP1652B25 |  | PWA BOM |  |
|  |  | ADD | 611004M00-024-G | RES,16.5KOhm,+/-0.1%,1/16W,G,SMD0402 | PANASONIC | ERA2AEB1652X |  | PWA BOM |  |
| 25 | PSPR5,PIPR5,PFPR5,PEPR5 |  | 61011H300-017-G | RES,316 Ohm,+/-1%,1/16W,G,SMD0402 | KOA SPEER ELECTRONICS, INC. | RK73H1ETTP3160F |  | PWA BOM |  |
|  |  | ADD | 61011H300-029-G | RES,316 Ohm,+/-1%,1/16W,G,SMD0402 | VISHAY | CRCW0402316RFKEDC |  | PWA BOM |  |
| 26 | PERR2,PHAR35 |  | 61011PE00-017-G | RES,8.87KOhm,+/-1%,1/16W,G,SMD0402 | KOA SPEER ELECTRONICS, INC. | RK73H1ETTP8871F |  | PWA BOM |  |
|  |  | ADD | 61011PE00-024-G | RES,8.87KOhm,+/-1%,1/16W,G,SMD0402 | VISHAY | ERJ2RKF8871X |  | PWA BOM |  |
|  |  | ADD | 61011PE00-029-G | RES,8.87KOhm,+/-1%,1/16W,G,SMD0402 | PANASONIC | CRCW04028K87FKEDC |  | PWA BOM |  |
| 27 | PFRR1 |  | 61011R400-017-G | RES,34.8KOhm,+/-1%,1/16W,G,SMD0402 | KOA SPEER ELECTRONICS, INC. | RK73H1ETTP3482F |  | PWA BOM |  |
|  |  | ADD | 61011R400-024-G | RES,34.8KOhm,+/-1%,1/16W,G,SMD0402 | PANASONIC | ERJ2RKF3482X |  | PWA BOM |  |
| 28 | PHAR6 |  | 610100R00-017-G | RES,3.74KOhm,+/-1%,1/10W,G,SMD0603 | KOA SPEER ELECTRONICS, INC. | RK73H1JTTD3741F |  | PWA BOM |  |
|  |  | ADD | 610100R00-024-G | RES,3.74KOhm,+/-1%,1/10W,G,SMD0603 | PANASONIC | ERJ3EKF3741V |  | PWA BOM |  |
|  |  | ADD | 610100R00-029-G | RES,3.74KOhm,+/-1%,1/10W,G,SMD0603 | VISHAY | CRCW06033K74FKEB |  | PWA BOM |  |
| 29 | PSIR2 |  | 61011MA00-017-G | RES,3.32KOhm,+/-1%,1/16W,G,SMD0402 | KOA SPEER ELECTRONICS, INC. | RK73H1ETTP3321F |  | PWA BOM |  |
|  |  | ADD | 61011MA00-024-G | RES,3.32KOhm,+/-1%,1/16W,G,SMD0402 | PANASONIC | ERJ2RKF3321X |  | PWA BOM |  |
|  |  | ADD | 61011MA00-029-G | RES,3.32KOhm,+/-1%,1/16W,G,SMD0402 | VISHAY | CRCW04023K32FKED |  | PWA BOM |  |
| 30 | PSUQ1,Q2,Q6 |  | 51030CQ00-185-G | MOS N,2N7002,60V,115mA,7.5ohm@5V,G,SOT23-3,SMD | FAIRCHILD SEMICONDUCTOR CORP | 2N7002 |  | PWA BOM |  |
|  |  | ADD | 510301N00-223-G | MOS N,2N7002LT1G,60V,0.115A,7.5ohm@5V,G,SOT23-3,SMD | ON SEMICONDUCTOR CORP | 2N7002LT1G |  | PWA BOM |  |
| 31 | R1492 |  | 610118800-017-G | RES,499KOhm,+/-1%,1/8W,G,SMD0805 | KOA SPEER ELECTRONICS, INC. | RK73H2ATTD4993F |  | PWA BOM |  |
|  |  | ADD | 610118800-024-G | RES,499KOhm,+/-1%,1/8W,G,SMD0805 | PANASONIC | ERJ6ENF4993V |  | PWA BOM |  |
| 32 | R1493 |  | 61011LF00-017-G | RES,499KOhm,+/-1%,1/16W,G,SMD0402 | KOA SPEER ELECTRONICS, INC. | RK73H1ETTP4993F |  | PWA BOM |  |
|  |  | ADD | 61011LF00-024-G | RES,499KOhm,+/-1%,1/16W,G,SMD0402 | PANASONIC | ERJ2RKF4993X |  | PWA BOM |  |
| OOOOOOOOOOOOOOOOOOOOOOOOOOOOOOOOOOOOOOOOOOOOOOOOOOOOOOOOOOOOOOOOOOOOOOOOOOOOOOOOOOOOOOOOOO | OOOOOOOOOOOOOOOOOOOOOOOOOOOOOOOOOOOOOOOOOOOOOOOOOOOOOOOOOOOOOOOOOOOOOOOOOOOOOOOOOOOOOOOOOO | OOOOOOOOOOOOOOOOOOOOOOOOOOOOOOOOOOOOOOOOOOOOOOOOOOOOOOOOOOOOOOOOOOOOOOOOOOOOOOOOOOOOOOOOOO | OOOOOOOOOOOOOOOOOOOOOOOOOOOOOOOOOOOOOOOOOOOOOOOOOOOOOOOOOOOOOOOOOOOOOOOOOOOOOOOOOOOOOOOOOO | OOOOOOOOOOOOOOOOOOOOOOOOOOOOOOOOOOOOOOOOOOOOOOOOOOOOOOOOOOOOOOOOOOOOOOOOOOOOOOOOOOOOOOOOOO | OOOOOOOOOOOOOOOOOOOOOOOOOOOOOOOOOOOOOOOOOOOOOOOOOOOOOOOOOOOOOOOOOOOOOOOOOOOOOOOOOOOOOOOOOO | OOOOOOOOOOOOOOOOOOOOOOOOOOOOOOOOOOOOOOOOOOOOOOOOOOOOOOOOOOOOOOOOOOOOOOOOOOOOOOOOOOOOOOOOOO | OOOOOOOOOOOOOOOOOOOOOOOOOOOOOOOOOOOOOOOOOOOOOOOOOOOOOOOOOOOOOOOOOOOOOOOOOOOOOOOOOOOOOOOOOO | OOOOOOOOOOOOOOOOOOOOOOOOOOOOOOOOOOOOOOOOOOOOOOOOOOOOOOOOOOOOOOOOOOOOOOOOOOOOOOOOOOOOOOOOOO | OOOOOOOOOOOOOOOOOOOOOOOOOOOOOOOOOOOOOOOOOOOOOOOOOOOOOOOOOOOOOOOOOOOOOOOOOOOOOOOOOOOOOOOOOO |
| Master Materials Change |  |  |  |  |  |  |  |  |  |
| Item | Foxconn P/N | Orig._Usage | New_Usage | Part Description | Manufacturer Full Name | Manufacturer P/N | RoHS | Location | Sheet |
| 1 | 0101EJD00-000-G | 0 | 1 | PCB,Zaius-MB EVT3-X02,OSP,Red,22L,22.20*13.00,G | GCE | 0101EJD00-000-G |  | (+)PCB | PWA BOM |
|  | 0101EJD00-000-G-A |  |  | PCB,Zaius-MB EVT3-X02,OSP,Red,22L,22.20*13.00,G | ISU | 0101EJD00-000-G |  |  | PWA BOM |
| 2 | 620103700-015-G | 175 | 174 | CAP,100nF,+/-10%,X7R,10V,G,SMD0402 | MURATA ELEC. NORTH AMERICA | GRM155R71A104K |  | (+)C84,C98,C793,C2130,C2186 (-)C203,C204,C205,C234,C235,C236 | PWA BOM |
|  | 620103700-023-G |  |  | CAP,100nF,+/-10%,X7R,10V,G,SMD0402 | TAIYO ELECTRIC IND.CO.LTD | LMK105B7104KV-F |  |  | PWA BOM |
|  | 620103700-026-G |  |  | CAP,100nF,+/-10%,X7R,10V,G,SMD0402 | SAMSUNG SEMICONDUCTOR | CL05B104KP5NNNC |  |  | PWA BOM |
| 3 | 62012WD00-015-G | 16 | 20 | CAP,4.7uF,+/-20%,X6S,6.3V,G,SMD0402 | MURATA ELEC. NORTH AMERICA | GRM155C80J475MEAAD |  | (+)C62,C147,C777,C860 | PWA BOM |
|  | 62012WD00-023-G |  |  | CAP,4.7uF,+/-20%,X6S,6.3V,G,SMD0402 | TAIYO ELECTRIC IND.CO.LTD | JMK105BC6475MV-F |  |  | PWA BOM |
| 4 | 62012NU00-015-G | 99 | 108 | CAP,1uF,+/-10%,X7R,6.3V,G,SMD0402 | MURATA ELEC. NORTH AMERICA | GRM155R70J105KA12D |  | (+)C134,C136,C146,C149,C181,C776,C799,C848,C849,C855,C903 (-)C202,C233 | PWA BOM |
|  | 62012NU00-026-G |  |  | CAP,1uF,+/-10%,X7R,6.3V,G,SMD0402 | SAMSUNG SEMICONDUCTOR | CL05B105KQ5NQNC |  |  | PWA BOM |
| 5 | 62012P100-015-G | 22 | 27 | CAP,2.2uF,+/-20%,X7S,10V,G,SMD0402 | MURATA ELEC. NORTH AMERICA | GRM155C71A225M |  | (+)C79,C142,C144,C226,C234,C813,C856,C864 (-)C206,C245,C757 | PWA BOM |
| 6 | 62011DF01-015-G | 304 | 283 | CAP,220nF,+/-10%,X7R,16V,G,SMD0402 | MURATA ELEC. NORTH AMERICA | GRM155R71C224K |  | (+)C66,C75,C76,C77,C81,C82,C97,C203,C206,C233,C235,C245,C796,C797,C798,C800 (-)C134,C136,C137,C138,C141,C142,C143,C144,C145,C146,C147,C148,C149,C150,C181,C182,C185,C186,C188,C847,C848,C849,C851,C852,C853,C854,C855,C856,C857,C858,C860,C864,C866,C897,C902,C903,C904 | PWA BOM |
|  | 62011DF00-026-G |  |  | CAP,220nF,+/-10%,X7R,16V,G,SMD0402 | SAMSUNG SEMICONDUCTOR | CL05B224KO5NNNC |  |  | PWA BOM |
|  | 62011DF00-023-G |  |  | CAP,220nF,+/-10%,X7R,16V,G,SMD0402 | TAIYO ELECTRIC IND.CO.LTD | EMK105B7224KV-FR |  |  | PWA BOM |
| 7 | 62011SJ00-026-G | 134 | 160 | CAP,470nF,+/-10%,X7R,6.3V,G,SMD0402 | SAMSUNG SEMICONDUCTOR | CL05B474KQ5NNNC |  | (+)C78,C95,C96,C137,C141,C143,C145,C148,C150,C183,C185,C186,C188,C236,C791,C792,C811,C847,C851,C852,C853,C854,C857,C858,C866,C902 | PWA BOM |
|  | 62011SJ00-023-G |  |  | CAP,470nF,+/-10%,X7R,6.3V,G,SMD0402 | TAIYO ELECTRIC IND.CO.LTD | JMK105B7474KV-F |  |  | PWA BOM |
| 8 | 62010G800-015-G | 4 | 3 | CAP,22nF,+/-10%,X7R,16V,G,SMD0402 | MURATA ELEC. NORTH AMERICA | GRM155R71C223K |  | (-)C2130 | PWA BOM |
|  | 62010G800-026-G |  |  | CAP,22nF,+/-10%,X7R,16V,G,SMD0402 | SAMSUNG SEMICONDUCTOR | CL05B223KO5NNNC |  |  | PWA BOM |
|  | 62010G800-023-G |  |  | CAP,22nF,+/-10%,X7R,16V,G,SMD0402 | TAIYO ELECTRIC IND.CO.LTD | EMK105B7223KV-F |  |  | PWA BOM |
| 9 | 62012H100-015-G | 7 | 11 | CAP,10uF,+/-20%,X6S,10V,G,SMD0603 | MURATA ELEC. NORTH AMERICA | GRM188C81A106M |  | (+)C182,C225,C273,C812 | PWA BOM |
|  | 62012H100-026-G |  |  | CAP,10uF,+/-20%,X6S,10V,G,SMD0603 | SAMSUNG SEMICONDUCTOR | CL10X106MP8NRNC |  |  | PWA BOM |
|  | 62012H100-023-G |  |  | CAP,10uF,+/-20%,X6S,10V,G,SMD0603 | TAIYO ELECTRIC IND.CO.LTD | LMK107BC6106MA-T |  |  | PWA BOM |
| 10 | 62012PS00-015-G | 500 | 495 | CAP,10uF,+/-20%,X6S,4V,G,SMD0402 | MURATA ELEC. NORTH AMERICA | GRM155C80G106M |  | (-)C225,C226,C264,C273,C2171 | PWA BOM |
|  | 62012PS00-023-G |  |  | CAP,10uF,+/-20%,X6S,4V,G,SMD0402 | TAIYO ELECTRIC IND.CO.LTD | AMK105CC6106MV-F |  |  | PWA BOM |
|  | 62012PS00-026-G |  |  | CAP,10uF,+/-20%,X6S,4V,G,SMD0402 | SAMSUNG | CL05X106MR5NUNC |  |  | PWA BOM |
| 11 | 620108B00-015-G | 0 | 4 | CAP,120pF,+/-5%,NPO(C0G),50V,G,SMD0402 | MURATA ELEC. NORTH AMERICA | GRM1555C1H121J |  | (+)C2182,C2183,C2184,C2185 | PWA BOM |
| 12 | 62011DA00-015-G | 0 | 6 | CAP,1uF,+/-10%,X7R,100V,G,SMD1206 | MURATA ELEC. NORTH AMERICA | GRM31CR72A105K |  | (+)PBMC27,PBAC27,PAMC27,PAAC27,PBAC111,PAAC111 | PWA BOM |
|  | 62011DA02-015-G |  |  | CAP,1uF,+/-10%,X7R,100V,G,SMD1206 | MURATA ELEC. NORTH AMERICA | GRM31CR72A105KA01K |  |  | PWA BOM |
|  | 62011DA00-023-G |  |  | CAP,1uF,+/-10%,X7R,100V,G,SMD1206 | TAIYO ELECTRIC IND.CO.LTD | HMK316B7105KL-T |  |  | PWA BOM |
|  | 62011DA00-026-G |  |  | CAP,1uF,+/-10%,X7R,100V,G,SMD1206 | SAMSUNG SEMICONDUCTOR | CL31B105KCHNNNE |  |  | PWA BOM |
| 13 | 51032DL00-237-G | 0 | 8 | MOS N,DMT10H014LSS-13,100V,8.9A,15m@10V,G,SO-8,SMD | DIODES INCORPORATION | DMT10H014LSS-13 |  | (+)PBMQ10,PBAQ10,PAMQ10,PAAQ10,PBFQ11,PBEQ11,PAFQ11,PAEQ11 | PWA BOM |
| 14 | 510100W00-237-G | 10 | 18 | TRANS N,MMBT3904-7-F,40V,0.2A,G,SOT23-3,SMD | DIODES INCORPORATION | MMBT3904-7-F |  | (+)PBMQ11,PBAQ11,PAMQ11,PAAQ11,PBFQ12,PBEQ12,PAFQ12,PAEQ12 | PWA BOM |
|  | 510101700-185-G |  |  | TRANS N,MMBT3904,40V,0.2A,G,SOT23-3,SMD | FAIRCHILD SEMICONDUCTOR CORP | MMBT3904 |  |  | PWA BOM |
| 15 | 610107A00-017-G | 699 | 714 | RES,0 Ohm,+/-5%,1/16W,G,SMD0402 | KOA SPEER ELECTRONICS, INC. | RK73Z1ETTP |  | (+)PUAR15,PSAR15,PRAR15,PQAR15,PPAR15,PIAR15,PFAR15,PEAR15,R1264,R1268,R1272,R1276,R1840,R1841,R1842 | PWA BOM |
|  | 610107A00-024-G |  |  | RES,0 Ohm,+/-5%,1/16W,G,SMD0402 | PANASONIC INDUSTRIAL CO.,LTD. | ERJ2GE0R00X |  |  | PWA BOM |
|  | 610107A00-029-G |  |  | RES,0 Ohm,+/-5%,1/16W,G,SMD0402 | VISHAY ENTER TECHNO LOGY.INC | CRCW04020000Z0ED |  |  | PWA BOM |
| 16 | 61100QV00-017-G | 6 | 8 | RES,49.9 Ohm,+/-0.5%,1/16W,G,SMD0402 | KOA SPEER ELECTRONICS, INC. | RN731ETTP49R9D50 |  | (+)PBAR57,PAAR57 | PWA BOM |
| 17 | 61100QG00-017-G | 4 | 2 | RES,649 Ohm,+/-0.1%,1/16W,G,SMD0402 | KOA SPEER ELECTRONICS, INC. | RN731ETTP6490B25 |  | (-)PBAR57,PAAR57 | PWA BOM |
|  | 61100QG00-024-G |  |  | RES,649 Ohm,+/-0.1%,1/16W,G,SMD0402 | PANASONIC INDUSTRIAL CO.,LTD. | ERA2AEB6490X |  |  | PWA BOM |
|  | 61100QG00-029-G |  |  | RES,649 Ohm,+/-0.1%,1/16W,G,SMD0402 | VISHAY ENTER TECHNO LOGY.INC | TNPW0402649RBEED |  |  | PWA BOM |
| 18 | 61010G500-017-G | 101 | 102 | RES,10KOhm,+/-1%,1/16W,G,SMD0402 | KOA SPEER ELECTRONICS, INC. | RK73H1ETTP1002F |  | (+)PHAR39,R906,R914 (-)R905,R915 | PWA BOM |
|  | 61010G500-029-G |  |  | RES,10KOhm,+/-1%,1/16W,G,SMD0402 | VISHAY ENTER TECHNO LOGY.INC | CRCW040210K0FKED |  |  | PWA BOM |
|  | 61010G500-024-G |  |  | RES,10KOhm,+/-1%,1/16W,G,SMD0402 | PANASONIC INDUSTRIAL CO.,LTD. | ERJ2RKF1002X |  |  | PWA BOM |
| 19 | 611003200-017-G | 32 | 34 | RES,10KOhm,+/-0.1%,1/16W,G,SMD0402 | KOA SPEER ELECTRONICS, INC. | RN731ETTP1002B25 |  | (+)PBMR26,PAMR26 | PWA BOM |
| 20 | 61010L100-017-G | 24 | 16 | RES,100KOhm,+/-1%,1/16W,G,SMD0402 | KOA SPEER ELECTRONICS, INC. | RK73H1ETTP1003F |  | (-)PBFR517,PBER517,PAFR517,PAER518,PBMR602,PBAR602,PAMR602,PAAR602 | PWA BOM |
|  | 61010L106-029-G |  |  | RES,100KOhm,+/-1%,1/16W,G,SMD0402 | VISHAY ENTER TECHNO LOGY.INC | CRCW0402100KFKEDC |  |  | PWA BOM |
|  | 61010L100-024-G |  |  | RES,100KOhm,+/-1%,1/16W,G,SMD0402 | PANASONIC INDUSTRIAL CO.,LTD. | ERJ2RKF1003X |  |  | PWA BOM |
| 21 | 61013A200-017-G | 8 | 4 | RES,6.8 Ohm,+/-1%,1/4W,G,SMD1206 | KOA SPEER ELECTRONICS, INC. | RK73H2BTTD6R80F |  | (-)PBFR513,PBER513,PAFR513,PAER513 | PWA BOM |
|  | 61013A200-029-G |  |  | RES,6.8 Ohm,+/-1%,1/4W,G,SMD1206 | VISHAY | CRCW12066R80FKEA |  |  | PWA BOM |
| 22 | ISL68137IRAZ-EVT3 | 0 | 8 | IC,PWM Controller,ISL68137IRAZ-T,G,QFN-48,SMD | INTERSIL CORPORATION | ISL68137IRAZ-EVT3 |  | (+)PBMU1,PBFU1,PBEU1,PBAU1,PAMU1,PAFU1,PAEU1,PAAU1 | PWA BOM |
| 23 | 61100RN00-017-G | 6 | 4 | RES,15.4KOhm,+/-0.1%,1/16W,G,SMD0402 | KOA SPEER ELECTRONICS, INC. | RN731ETTP1542B25 |  | (-)PBMR26,PAMR26 | PWA BOM |
| 24 | 61012C600-017-G | 6 | 4 | RES,12.4 Ohm,+/-1%,1/16W,G,SMD0402 | KOA SPEER ELECTRONICS, INC. | RK73H1ETTP12R4F |  | (-)PBMR57,PAMR57 | PWA BOM |
| 25 | 61015NJ00-017-G | 0 | 4 | RES,6.04 Ohm,+/-1%,1/4W,G,SMD1206 | KOA SPEER ELECTRONICS, INC. | RK73H2BTTD6R04F |  | (+)PBFR513,PBER513,PAFR513,PAER513 | PWA BOM |
| 26 | 880302600-53N-G | 6 | 4 | Converter,input 0V~52V,120W,G,VTM48RP015C076AG0 | Vicor Corporation | VTM48RP015C076AG0 |  | (-)PBMU4,PAMU4 | PWA BOM |
| 27 | 620109700-015-G | 22 | 21 | CAP,3.3nF,+/-10%,X7R,50V,G,SMD0402 | MURATA ELEC. NORTH AMERICA | GRM155R71H332K |  | (-)PETC7 | PWA BOM |
|  | 620109700-026-G |  |  | CAP,3.3nF,+/-10%,X7R,50V,G,SMD0402 | SAMSUNG SEMICONDUCTOR | CL05B332KB5NNNC |  |  | PWA BOM |
|  | 620109700-023-G |  |  | CAP,3.3nF,+/-10%,X7R,50V,G,SMD0402 | TAIYO ELECTRIC IND.CO.LTD | UMK105B7332KV-F |  |  | PWA BOM |
| 28 | 61011GE00-017-G | 0 | 2 | RES,21 Ohm,+/-1%,1/16W,G,SMD0402 | KOA SPEER ELECTRONICS, INC. | RK73H1ETTP21R0F |  | (+)PBMR57,PAMR57 | PWA BOM |
| 29 | 61010R900-017-G | 0 | 4 | RES,27.4KOhm,+/-1%,1/10W,G,SMD0603 | KOA SPEER ELECTRONICS, INC. | RK73H1JTTD2742F |  | (+)PAMR66,PBMR69,PBMR76,PAMR76 | PWA BOM |
| 30 | 610114B00-017-G | 1 | 2 | RES,2.49KOhm,+/-1%,1/16W,G,SMD0402 | KOA SPEER ELECTRONICS, INC. | RK73H1ETTP2491F |  | (+)PBNR11 | PWA BOM |
|  | 610114B00-024-G |  |  | RES,2.49KOhm,+/-1%,1/16W,G,SMD0402 | PANASONIC | ERJ2RKF2491X |  |  | PWA BOM |
|  | 610114B00-029-G |  |  | RES,2.49KOhm,+/-1%,1/16W,G,SMD0402 | VISHAY | CRCW04022K49FKED |  |  | PWA BOM |
| 31 | 61011CJ00-017-G | 1 | 2 | RES,365 Ohm,+/-1%,1/16W,G,SMD0402 | KOA SPEER ELECTRONICS, INC. | RK73H1ETTP3650F |  | (+)PBNR14 | PWA BOM |
|  | 61011CJ00-024-G |  |  | RES,365 Ohm,+/-1%,1/16W,G,SMD0402 | PANASONIC | ERJ2RKF3650X |  |  | PWA BOM |
|  | 61011CJ00-029-G |  |  | RES,365 Ohm,+/-1%,1/16W,G,SMD0402 | VISHAY | CRCW0402365RFKEDC |  |  | PWA BOM |
| 32 | 61011CS00-017-G | 0 | 2 | RES,750KOhm,+/-1%,1/16W,G,SMD0402 | KOA SPEER ELECTRONICS, INC. | RK73H1ETTP7503F |  | (+)PBNR24,PANR24 | PWA BOM |
| 33 | 62011AM00-015-G | 0 | 1 | CAP,6.8nF,+/-10%,X7R,50V,G,SMD0402 | MURATA ELEC. NORTH AMERICA | GRM155R71H682K |  | (+)PETC7 | PWA BOM |
| 34 | 51032D100-237-G | 1 | 2 | MOS N,DMN10H220L-7,100V,1.6A,220m@10V,G,SOT-23-3,SMD | DIODES INCORPORATION | DMN10H220L-7 |  | (+)PHAQ6 | PWA BOM |
| 35 | 610124C00-017-G | 0 | 4 | RES,57.6 Ohm,+/-1%,1/16W,G,SMD0402 | KOA SPEER ELECTRONICS, INC. | RK73H1ETTP57R6F |  | (+)R1836,R1837,R1838,R1839 | PWA BOM |
|  | 610124C00-024-G |  |  | RES,57.6 Ohm,+/-1%,1/16W,G,SMD0402 | PANASONIC | ERJ2RKF57R6X |  |  | PWA BOM |
| 36 | 51030CQ00-185-G | 1 | 3 | MOS N,2N7002,60V,115mA,7.5ohm@5V,G,SOT23-3,SMD | FAIRCHILD SEMICONDUCTOR CORP | 2N7002 |  | (+)Q2,Q6 | PWA BOM |
|  | 510301N00-223-G |  |  | MOS N,2N7002LT1G,60V,0.115A,7.5ohm@5V,G,SOT23-3,SMD | ON SEMICONDUCTOR CORP | 2N7002LT1G |  |  | PWA BOM |
| 37 | 510503B00-223-G | 2 | 1 | MOS N/N,NTZD3154NT1G,20V,0.54A,550m24.5V,G,SOT563-6,SMD | ON SEMICONDUCTOR CORP | NTZD3154NT1G |  | (-)QN3 | PWA BOM |
| 38 | 51030QP00-237-G | 43 | 44 | MOS N,BSS138W-7-F,50V,0.2A,3.5ohm@10V,G,SOT323-3,SMD | DIODES INCORPORATION | BSS138W-7-F |  | (+)Q93 | PWA BOM |
| 39 | 610100T00-017-G | 108 | 107 | RES,1KOhm,+/-5%,1/16W,G,SMD0402 | KOA SPEER ELECTRONICS, INC. | RK73B1ETTP102J |  | (-)R1802 | PWA BOM |
|  | 610100T00-024-G |  |  | RES,1KOhm,+/-5%,1/16W,G,SMD0402 | PANASONIC INDUSTRIAL CO.,LTD. | ERJ2GEJ102X |  |  | PWA BOM |
| 40 | 61100LV00-017-G | 13 | 9 | RES,10KOhm,+/-1%,1/16W,G,SMD0402 | KOA SPEER ELECTRONICS, INC. | RN731ETTP1002F50 |  | (-)R1264,R1268,R1272,R1276 | PWA BOM |
| 41 | 610112800-017-G | 2 | 1 | RES,6.04KOhm,+/-1%,1/16W,G,SMD0402 | KOA SPEER ELECTRONICS, INC. | RK73H1ETTP6041F |  | (-)PBNR11 | PWA BOM |
|  | 610112800-029-G |  |  | RES,6.04KOhm,+/-1%,1/16W,G,SMD0402 | VISHAY ENTER TECHNO LOGY.INC | CRCW04026K04FKED |  |  | PWA BOM |
| 42 | 310109D00-031-G | 2 | 3 | IC,Gate&Inverter,74LVC1G32GW,1.65~5.5V,G,TSSOP-5,SMD | NXP SEMICONDUCTORS | 74LVC1G32GW |  | (+)U180 | PWA BOM |
| 43 | 3406AUA00-309-G | 0 | 36 | CONN,Pin Header,1X2,V/T,Bla,2.54mm,10u,G,SMD-2 | SAMTEC INC. | ASP-195607-01 |  | (+)J105,J106,J107,J108,J109,J110,J111,J112,J113,J114,J115,J116,J118,J119,J120,J121,J122,J123,J124,J126,J127,J128,J129,J130,J131,J132,J133,J134,J135,J136,J137,J138,J139,J140,J141,J149 | PWA BOM |
| 44 | 340672300-317-G | 0 | 1 | CONN,Pin Header,1X4,V/T,Bla,2.54mm,30u,G,SMD-4 | MOLEX INCORPORATED | 87898-0455 |  | (+)J148 | PWA BOM |
| 45 | TBD-PI3753-00-LGIZ | 0 | 2 | IC,Regulator,PI3753-00,ADJ,4A,G,LGA-71,SMD | Vicor Corporation | PI3753-00-LGIZ |  | (+)PBAU3,PAAU3 | PWA BOM |
| 46 | PI3755-02-LGIZ | 0 | 6 | IC,Regulator,PI3755-02-LGIZ,ADJ,4A,G,LGA-71,SMD | Vicor Corporation | PI3755-02-LGIZ |  | (+)PBFU3,PBEU3,PAMU3,PAFU3,PAEU3,PBMU3 | PWA BOM |
| 47 | 880302800-53N-G | 0 | 2 | Converter,input 0V~60V,131W,G,VTM48MP010C105AG0 | Vicor Corporation | VTM48MP010C105AG0 |  | (+)PAMU4,PBMU4 | PWA BOM |
| 48 | 0101E6K00-000-G | 1 | 0 | PCB,Zaius-MB EVT2-X01,OSP,Red,22L,22.20*13.00,G | GCE | 0101E6K00-000-G |  | (-)PCB | PWA BOM |
|  | 0101E6K00-000-G-A |  |  | PCB,Zaius-MB EVT2-X01,OSP,Red,22L,22.20*13.00,G | ISU | 0101E6K00-000-G |  |  | PWA BOM |
|  | 0101E6K00-000-G-B |  |  | PCB,Zaius-MB EVT2-X01,OSP,Red,22L,22.20*13.00,G | FOUNDER | 0101E6K00-000-G |  |  | PWA BOM |
| 49 | 620107G00-015-G | 4 | 0 | CAP,47nF,+/-10%,X7R,16V,G,SMD0402 | MURATA ELEC. NORTH AMERICA | GRM155R71C473K |  | (-)C183,C184,C231,C232 | PWA BOM |
|  | 620107G00-023-G |  |  | CAP,47nF,+/-10%,X7R,16V,G,SMD0402 | TAIYO ELECTRIC IND.CO.LTD | EMK105B7473KV-F |  |  | PWA BOM |
|  | 620107G00-026-G |  |  | CAP,47nF,+/-10%,X7R,16V,G,SMD0402 | SAMSUNG SEMICONDUCTOR | CL05B473KO5NNNC |  |  | PWA BOM |
| 50 | 62011DA02-015-G | 6 | 0 | CAP,1uF,+/-10%,X7R,100V,G,SMD1206 | MURATA ELEC. NORTH AMERICA | GRM31CR72A105KA01K |  | (-)PBMC27,PBAC27,PAMC27,PAAC27,PBAC111,PAAC111 | PWA BOM |
|  | 62011DA00-023-G |  |  | CAP,1uF,+/-10%,X7R,100V,G,SMD1206 | TAIYO ELECTRIC IND.CO.LTD | HMK316B7105KL-T |  |  | PWA BOM |
|  | 62011DA00-026-G |  |  | CAP,1uF,+/-10%,X7R,100V,G,SMD1206 | SAMSUNG SEMICONDUCTOR | CL31B105KCHNNNE |  |  | PWA BOM |
| 51 | 510101700-185-G | 8 | 0 | TRANS N,MMBT3904,40V,0.2A,G,SOT23-3,SMD | FAIRCHILD SEMICONDUCTOR CORP | MMBT3904 |  | (-)PBMQ11,PBAQ11,PAMQ11,PAAQ11,PBFQ12,PBEQ12,PAFQ12,PAEQ12 | PWA BOM |
| 52 | 320242200-230-G | 8 | 0 | IC,PWM Controller,ISL68137IRAZ-T,G,QFN-48,SMD | INTERSIL CORPORATION | ISL68137IRAZ-T |  | (-)PBMU1,PBFU1,PBEU1,PBAU1,PAMU1,PAFU1,PAEU1,PAAU1 | PWA BOM |
| 53 | 320148D00-53N-G | 6 | 0 | IC,Regulator,PI3755-01-LGIZ,ADJ,4A,G,LGA-71,SMD | Vicor Corporation | PI3755-01-LGIZ |  | (-)PBMU3,PBFU3,PBEU3,PAMU3,PAFU3,PAEU3 | PWA BOM |
| 54 | 610107K00-017-G | 4 | 0 | RES,24.9KOhm,+/-1%,1/10W,G,SMD0603 | KOA SPEER ELECTRONICS, INC. | RK73H1JTTD2492F |  | (-)PAMR66,PBMR69,PBMR76,PAMR76 | PWA BOM |
| 55 | 61010FF00-017-G | 1 | 0 | RES,150 Ohm,+/-1%,1/16W,G,SMD0402 | KOA SPEER ELECTRONICS, INC. | RK73H1ETTP1500F |  | (-)PBNR14 | PWA BOM |
|  | 61010FF00-024-G |  |  | RES,150 Ohm,+/-1%,1/16W,G,SMD0402 | PANASONIC INDUSTRIAL CO.,LTD. | ERJ2RKF1500X |  |  | PWA BOM |
| 56 | 510301N00-223-G | 2 | 0 | MOS N,2N7002LT1G,60V,0.115A,7.5ohm@5V,G,SOT23-3,SMD | ON SEMICONDUCTOR CORP | 2N7002LT1G |  | (-)Q2,Q6 | PWA BOM |
| 57 | 61011CY00-017-G | 4 | 0 | RES,5.6KOhm,+/-1%,1/16W,G,SMD0402 | KOA SPEER ELECTRONICS, INC. | RK73H1ETTP5601F |  | (-)R1266,R1270,R1274,R1278 | PWA BOM |
|  | 61011CY00-029-G |  |  | RES,5.6KOhm,+/-1%,1/16W,G,SMD0402 | VISHAY ENTER TECHNO LOGY.INC | CRCW04025K60FKED |  |  | PWA BOM |
| 58 | ASP-195607-01 | 39 | 0 | CONN,Pin Header,1X2,V/T,Bla,2.54mm,10u,G,SMD-2 | SAMTEC INC. | ASP-195607-01 |  | (-)J104,J105,J106,J107,J108,J109,J110,J111,J112,J113,J114,J115,J116,J117,J118,J119,J120,J121,J122,J123,J124,J125,J126,J127,J128,J129,J130,J131,J132,J133,J134,J135,J136,J137,J138,J139,J140,J141,J149 | PWA BOM |
| 59 | 340670200-317-G | 1 | 0 | CONN,Pin Header,1X4,V/T,Bla,2.54mm,30u,G,SMD-4 | MOLEX INCORPORATED | 87898-0425 |  | (-)J148 | PWA BOM |
| 60 | DMT10H014LSS | 8 | 0 | MOS N,DMT10H014LSS,100V,7.9A,18m@6V,G,SO8,SMD | DIODES INCORPORATION | DMT10H014LSS |  | (-)PBMQ10,PBAQ10,PAMQ10,PAAQ10,PBFQ11,PBEQ11,PAFQ11,PAEQ11 | PWA BOM |
| 61 | PI3753-00-LGIZ | 2 | 0 | IC,Regulator,PI3753-00,ADJ,4A,G,LGA-71,SMD | Vicor Corporation | PI3753-00-LGIZ |  | (-)PBAU3,PAAU3 | PWA BOM |
| OOOOOOOOOOOOOOOOOOOOOOOOOOOOOOOOOOOOOOOOOOOOOOOOOOOOOOOOOOOOOOOOOOOOOOOOOOOOOOOOOOOOOOOOOO | OOOOOOOOOOOOOOOOOOOOOOOOOOOOOOOOOOOOOOOOOOOOOOOOOOOOOOOOOOOOOOOOOOOOOOOOOOOOOOOOOOOOOOOOOO | OOOOOOOOOOOOOOOOOOOOOOOOOOOOOOOOOOOOOOOOOOOOOOOOOOOOOOOOOOOOOOOOOOOOOOOOOOOOOOOOOOOOOOOOOO | OOOOOOOOOOOOOOOOOOOOOOOOOOOOOOOOOOOOOOOOOOOOOOOOOOOOOOOOOOOOOOOOOOOOOOOOOOOOOOOOOOOOOOOOOO | OOOOOOOOOOOOOOOOOOOOOOOOOOOOOOOOOOOOOOOOOOOOOOOOOOOOOOOOOOOOOOOOOOOOOOOOOOOOOOOOOOOOOOOOOO | OOOOOOOOOOOOOOOOOOOOOOOOOOOOOOOOOOOOOOOOOOOOOOOOOOOOOOOOOOOOOOOOOOOOOOOOOOOOOOOOOOOOOOOOOO | OOOOOOOOOOOOOOOOOOOOOOOOOOOOOOOOOOOOOOOOOOOOOOOOOOOOOOOOOOOOOOOOOOOOOOOOOOOOOOOOOOOOOOOOOO | OOOOOOOOOOOOOOOOOOOOOOOOOOOOOOOOOOOOOOOOOOOOOOOOOOOOOOOOOOOOOOOOOOOOOOOOOOOOOOOOOOOOOOOOOO | OOOOOOOOOOOOOOOOOOOOOOOOOOOOOOOOOOOOOOOOOOOOOOOOOOOOOOOOOOOOOOOOOOOOOOOOOOOOOOOOOOOOOOOOOO |  |
| TLA Parts Change |  |  |  |  |  |  |  |  |  |
| Item | Foxconn P/N | Qty | Part Description | Manufacturer Full Name | Manufacturer P/N | RoHS | Location | Remark |  |
| 1 | 48011U800-13E-G | 2 | Heat sink (40x80x25mm) | Aavid | 360579 | G |  | In New BOM |  |
|  | 48011U100-H8U-G |  | Heat sink (40x80x25mm) 2nd | Furukawa | HS855360 | G |  | In New BOM |  |
|  | 48011U800-13E-G | 2 | Heat sink (40x80x25mm) | Aavid | 360579 | G |  | In Old BOM |  |
|  | 48011U100-H8U-G |  | Heat sink (40x80x25mm) 2nd | Furukawa | HS855360 | G |  | In Old BOM |  |
|  | 48011VF00-13E-G |  | Heat sink L type (40x80x25,8) with Mylar | Aavid | 361115 | G |  | In Old BOM |  |
| BOM Change List Date:Fri Jan 06 09:38:17 GMT+08:00 2017 |  |  |  |  |  |  |  |  |  |
| New BOM file : ZAIUS-MB-EVT3-HW-EBOM-X00_20161228-add 2nd source_X15-20170106.xls |  |  |  |  |  |  |  |  |  |
| Old BOM file :  ZAIUS-MB-EVT3-HW-EBOM-X00_20161228-add 2nd source_X14-20170102.xls |  |  |  |  |  |  |  |  |  |
| ##### Add Parts |  |  |  |  |  |  |  |  |  |
| Item | Location | Qty | Foxconn P/N | Part Description | Manufacturer Full Name | Manufacturer P/N | RoHS | Sheet |  |
| ##### Remove Parts |  |  |  |  |  |  |  |  |  |
| Item | Location | Qty | Foxconn P/N | Part Description | Manufacturer Full Name | Manufacturer P/N | RoHS | Sheet |  |
| 1 | R909,R921 | 2 | 610107A00-017-G | RES,0 Ohm,+/-5%,1/16W,G,SMD0402 | KOA SPEER ELECTRONICS, INC. | RK73Z1ETTP |  | PWA BOM |  |
|  |  |  | 610107A00-024-G | RES,0 Ohm,+/-5%,1/16W,G,SMD0402 | PANASONIC INDUSTRIAL CO.,LTD. | ERJ2GE0R00X |  | PWA BOM |  |
|  |  |  | 610107A00-029-G | RES,0 Ohm,+/-5%,1/16W,G,SMD0402 | VISHAY ENTER TECHNO LOGY.INC | CRCW04020000Z0ED |  | PWA BOM |  |
| ##### Change Parts |  |  |  |  |  |  |  |  |  |
| Item | Location | Qty | Foxconn P/N | Part Description | Manufacturer Full Name | Manufacturer P/N | RoHS | Sheet | Remark |
| 1 | C2182,C2183,C2184,C2185 | 4 | 620108B00-015-G | CAP,120pF,+/-5%,NPO(C0G),50V,G,SMD0402 | MURATA ELEC. NORTH AMERICA | GRM1555C1H121J |  | PWA BOM | In New BOM |
|  |  |  | 620108B00-023-G | CAP,120pF,+/-5%,NPO(C0G),50V,G,SMD0402 | TAIYO | UMK105CG121JV-F |  | PWA BOM | In New BOM |
|  |  |  | 620108B00-026-G | CAP,120pF,+/-5%,NPO(C0G),50V,G,SMD0402 | SAMSUNG | CL05C121JB5NNNC |  | PWA BOM | In New BOM |
|  | C2182,C2183,C2184,C2185 | 4 | 620108B00-015-G | CAP,120pF,+/-5%,NPO(C0G),50V,G,SMD0402 | MURATA ELEC. NORTH AMERICA | GRM1555C1H121J |  | PWA BOM | In Old BOM |
| 2 | PBMR26,PAMR26,PBMR97,PAMR97,PBMR98,PAMR98,PBER99,PAFR99,PAER99,PBMR100,PBFR100,PBER100,PAMR100,PAFR100,PAER100,PBFR101,PBMR102,PBER102,PAMR102,PAFR102,PAER102,PBFR103,PBAR103,PAAR103,PBER104,PBAR104,PAFR104,PAER104,PAAR104,PBFR105,PBAR106,PAAR106,PBAR108,PAAR108 | 34 | 611003200-017-G | RES,10KOhm,+/-0.1%,1/16W,G,SMD0402 | KOA SPEER ELECTRONICS, INC. | RN731ETTP1002B25 |  | PWA BOM | In New BOM |
|  |  |  | 611003200-024-G | RES,10KOhm,+/-0.1%,1/16W,G,SMD0402 | PANASONIC | ERA2AEB103X |  | PWA BOM | In New BOM |
|  | PBMR26,PAMR26,PBMR97,PAMR97,PBMR98,PAMR98,PBER99,PAFR99,PAER99,PBMR100,PBFR100,PBER100,PAMR100,PAFR100,PAER100,PBFR101,PBMR102,PBER102,PAMR102,PAFR102,PAER102,PBFR103,PBAR103,PAAR103,PBER104,PBAR104,PAFR104,PAER104,PAAR104,PBFR105,PBAR106,PAAR106,PBAR108,PAAR108 | 34 | 611003200-017-G | RES,10KOhm,+/-0.1%,1/16W,G,SMD0402 | KOA SPEER ELECTRONICS, INC. | RN731ETTP1002B25 |  | PWA BOM | In Old BOM |
| 3 | PBMR57,PAMR57 | 2 | 61011GE00-017-G | RES,21 Ohm,+/-1%,1/16W,G,SMD0402 | KOA SPEER ELECTRONICS, INC. | RK73H1ETTP21R0F |  | PWA BOM | In New BOM |
|  |  |  | 61011GE00-024-G | RES,21 Ohm,+/-1%,1/16W,G,SMD0402 | PANASONIC | ERJ2RKF21R0X |  | PWA BOM | In New BOM |
|  |  |  | 61011GE00-029-G | RES,21 Ohm,+/-1%,1/16W,G,SMD0402 | VISHAY | CRCW040221R0FKED |  | PWA BOM | In New BOM |
|  | PBMR57,PAMR57 | 2 | 61011GE00-017-G | RES,21 Ohm,+/-1%,1/16W,G,SMD0402 | KOA SPEER ELECTRONICS, INC. | RK73H1ETTP21R0F |  | PWA BOM | In Old BOM |
| 4 | PBNR24,PANR24 | 2 | 61011CS00-017-G | RES,750KOhm,+/-1%,1/16W,G,SMD0402 | KOA SPEER ELECTRONICS, INC. | RK73H1ETTP7503F |  | PWA BOM | In New BOM |
|  |  |  | 61011CS00-011-G | RES,750KOhm,+/-1%,1/16W,G,SMD0402 | YAGEO | RC0402FR-07750KL |  | PWA BOM | In New BOM |
|  | PBNR24,PANR24 | 2 | 61011CS00-017-G | RES,750KOhm,+/-1%,1/16W,G,SMD0402 | KOA SPEER ELECTRONICS, INC. | RK73H1ETTP7503F |  | PWA BOM | In Old BOM |
| 5 | PSLC16,PSFC16,PSEC16,PSDC16,PEEC16,PEDC16 | 6 | 62012CM01-015-G | CAP,10uF,+/-20%,X6S,4V,G,SMD0603 | MURATA ELEC. NORTH AMERICA | GRM188C80G106M |  | PWA BOM | In New BOM |
|  |  |  | 62012CM00-026-G | CAP,10uF,+/-20%,X6S,4V,G,SMD0603 | SAMSUNG | CL10X106MR8NNNC |  | PWA BOM | In New BOM |
|  |  |  | 62012CM00-023-G | CAP,10uF,+/-20%,X6S,4V,G,SMD0603 | TAIYO ELECTRIC IND.CO.LTD | AMK107AC6106MA-T |  | PWA BOM | In New BOM |
|  | PSLC16,PSFC16,PSEC16,PSDC16,PEEC16,PEDC16 | 6 | 62012CM01-015-G | CAP,10uF,+/-20%,X6S,4V,G,SMD0603 | MURATA ELEC. NORTH AMERICA | GRM188C80G106M |  | PWA BOM | In Old BOM |
|  |  |  | 62012CM00-026-G | CAP,10uF,+/-20%,X6S,4V,G,SMD0603 | SAMSUNG | CL10X106MR8NNNC |  | PWA BOM | In Old BOM |
| 6 | PBMC27,PBAC27,PAMC27,PAAC27,PBAC111,PAAC111 | 6 | 62011DA02-015-G | CAP,1uF,+/-10%,X7R,100V,G,SMD1206 | MURATA ELEC. NORTH AMERICA | GRM31CR72A105KA01K |  | PWA BOM | In New BOM |
|  |  |  | 62011DA00-015-G | CAP,1uF,+/-10%,X7R,100V,G,SMD1206 | MURATA ELEC. NORTH AMERICA | GRM31CR72A105K |  | PWA BOM | In New BOM |
|  |  |  | 62011DA00-023-G | CAP,1uF,+/-10%,X7R,100V,G,SMD1206 | TAIYO ELECTRIC IND.CO.LTD | HMK316B7105KL-T |  | PWA BOM | In New BOM |
|  |  |  | 62011DA00-026-G | CAP,1uF,+/-10%,X7R,100V,G,SMD1206 | SAMSUNG SEMICONDUCTOR | CL31B105KCHNNNE |  | PWA BOM | In New BOM |
|  | PBMC27,PBAC27,PAMC27,PAAC27,PBAC111,PAAC111 | 6 | 62011DA02-015-G | CAP,1uF,+/-10%,X7R,100V,G,SMD1206 | MURATA ELEC. NORTH AMERICA | GRM31CR72A105KA01K |  | PWA BOM | In Old BOM |
|  |  |  | 62011DA00-023-G | CAP,1uF,+/-10%,X7R,100V,G,SMD1206 | TAIYO ELECTRIC IND.CO.LTD | HMK316B7105KL-T |  | PWA BOM | In Old BOM |
|  |  |  | 62011DA00-026-G | CAP,1uF,+/-10%,X7R,100V,G,SMD1206 | SAMSUNG SEMICONDUCTOR | CL31B105KCHNNNE |  | PWA BOM | In Old BOM |
| 7 | PCIE1,PCIE5 | 2 | 10061913-102HLF | CONN,PCIE-8X,V/T,Bla,1mm,30u,G,SMD-98 | FCI CONNECTORS HONGKONG LTD. | 10061913-102HLF |  | PWA BOM | In New BOM |
|  | PCIE1,PCIE5 | 2 | 340316300-G78-G | CONN,PCIE-8X,V/T,Bla,1mm,30u,G,SMD-98 | FCI CONNECTORS HONGKONG LTD. | 10061913-102PLF |  | PWA BOM | In Old BOM |
| 8 | PCIE2,PCIE3,PCIE4 | 3 | 10061913-103HLF | CONN,PCIE-16X,V/T,Bla,1mm,30u,G,SMD-164 | FCI CONNECTORS HONGKONG LTD. | 10061913-103HLF |  | PWA BOM | In New BOM |
|  | PCIE2,PCIE3,PCIE4 | 3 | 34031U600-G78-G | CONN,PCIE-16X,V/T,Bla,1mm,30u,G,SMD-164 | FCI CONNECTORS HONGKONG LTD. | 10061913-103BLF |  | PWA BOM | In Old BOM |
| ##### Change Revision |  |  |  |  |  |  |  |  |  |
| Sheet | REV OF BOM | CUSTOMER | CUSTOMER P/N | PWA PN | PWA DESCRIPTION | PWA REV | DATE | Remark |  |
| PWA BOM | X15 | Google |  |  |  |  |  | In New BOM |  |
| PWA BOM | X14 | Google |  |  |  |  |  | In Old BOM |  |
| OOOOOOOOOOOOOOOOOOOOOOOOOOOOOOOOOOOOOOOOOOOOOOOOOOOOOOOOOOOOOOOOOOOOOOOOOOOOOOOOOOOOOOOOOO | OOOOOOOOOOOOOOOOOOOOOOOOOOOOOOOOOOOOOOOOOOOOOOOOOOOOOOOOOOOOOOOOOOOOOOOOOOOOOOOOOOOOOOOOOO | OOOOOOOOOOOOOOOOOOOOOOOOOOOOOOOOOOOOOOOOOOOOOOOOOOOOOOOOOOOOOOOOOOOOOOOOOOOOOOOOOOOOOOOOOO | OOOOOOOOOOOOOOOOOOOOOOOOOOOOOOOOOOOOOOOOOOOOOOOOOOOOOOOOOOOOOOOOOOOOOOOOOOOOOOOOOOOOOOOOOO | OOOOOOOOOOOOOOOOOOOOOOOOOOOOOOOOOOOOOOOOOOOOOOOOOOOOOOOOOOOOOOOOOOOOOOOOOOOOOOOOOOOOOOOOOO | OOOOOOOOOOOOOOOOOOOOOOOOOOOOOOOOOOOOOOOOOOOOOOOOOOOOOOOOOOOOOOOOOOOOOOOOOOOOOOOOOOOOOOOOOO | OOOOOOOOOOOOOOOOOOOOOOOOOOOOOOOOOOOOOOOOOOOOOOOOOOOOOOOOOOOOOOOOOOOOOOOOOOOOOOOOOOOOOOOOOO | OOOOOOOOOOOOOOOOOOOOOOOOOOOOOOOOOOOOOOOOOOOOOOOOOOOOOOOOOOOOOOOOOOOOOOOOOOOOOOOOOOOOOOOOOO | OOOOOOOOOOOOOOOOOOOOOOOOOOOOOOOOOOOOOOOOOOOOOOOOOOOOOOOOOOOOOOOOOOOOOOOOOOOOOOOOOOOOOOOOOO | OOOOOOOOOOOOOOOOOOOOOOOOOOOOOOOOOOOOOOOOOOOOOOOOOOOOOOOOOOOOOOOOOOOOOOOOOOOOOOOOOOOOOOOOOO |
| Second Source Change |  |  |  |  |  |  |  |  |  |
| Item | Location | Change Type | Foxconn P/N | Part Description | Manufacturer Full Name | Manufacturer P/N | RoHS | Sheet |  |
| 1 | C2182,C2183,C2184,C2185 |  | 620108B00-015-G | CAP,120pF,+/-5%,NPO(C0G),50V,G,SMD0402 | MURATA ELEC. NORTH AMERICA | GRM1555C1H121J |  | PWA BOM |  |
|  |  | ADD | 620108B00-023-G | CAP,120pF,+/-5%,NPO(C0G),50V,G,SMD0402 | TAIYO | UMK105CG121JV-F |  | PWA BOM |  |
|  |  | ADD | 620108B00-026-G | CAP,120pF,+/-5%,NPO(C0G),50V,G,SMD0402 | SAMSUNG | CL05C121JB5NNNC |  | PWA BOM |  |
| 2 | PBMR26,PAMR26,PBMR97,PAMR97,PBMR98,PAMR98,PBER99,PAFR99,PAER99,PBMR100,PBFR100,PBER100,PAMR100,PAFR100,PAER100,PBFR101,PBMR102,PBER102,PAMR102,PAFR102,PAER102,PBFR103,PBAR103,PAAR103,PBER104,PBAR104,PAFR104,PAER104,PAAR104,PBFR105,PBAR106,PAAR106,PBAR108,PAAR108 |  | 611003200-017-G | RES,10KOhm,+/-0.1%,1/16W,G,SMD0402 | KOA SPEER ELECTRONICS, INC. | RN731ETTP1002B25 |  | PWA BOM |  |
|  |  | ADD | 611003200-024-G | RES,10KOhm,+/-0.1%,1/16W,G,SMD0402 | PANASONIC | ERA2AEB103X |  | PWA BOM |  |
| 3 | PBMR57,PAMR57 |  | 61011GE00-017-G | RES,21 Ohm,+/-1%,1/16W,G,SMD0402 | KOA SPEER ELECTRONICS, INC. | RK73H1ETTP21R0F |  | PWA BOM |  |
|  |  | ADD | 61011GE00-024-G | RES,21 Ohm,+/-1%,1/16W,G,SMD0402 | PANASONIC | ERJ2RKF21R0X |  | PWA BOM |  |
|  |  | ADD | 61011GE00-029-G | RES,21 Ohm,+/-1%,1/16W,G,SMD0402 | VISHAY | CRCW040221R0FKED |  | PWA BOM |  |
| 4 | PBNR24,PANR24 |  | 61011CS00-017-G | RES,750KOhm,+/-1%,1/16W,G,SMD0402 | KOA SPEER ELECTRONICS, INC. | RK73H1ETTP7503F |  | PWA BOM |  |
|  |  | ADD | 61011CS00-011-G | RES,750KOhm,+/-1%,1/16W,G,SMD0402 | YAGEO | RC0402FR-07750KL |  | PWA BOM |  |
| 5 | PSLC16,PSFC16,PSEC16,PSDC16,PEEC16,PEDC16 |  | 62012CM01-015-G | CAP,10uF,+/-20%,X6S,4V,G,SMD0603 | MURATA ELEC. NORTH AMERICA | GRM188C80G106M |  | PWA BOM |  |
|  |  | NO | 62012CM00-026-G | CAP,10uF,+/-20%,X6S,4V,G,SMD0603 | SAMSUNG | CL10X106MR8NNNC |  | PWA BOM |  |
|  |  | ADD | 62012CM00-023-G | CAP,10uF,+/-20%,X6S,4V,G,SMD0603 | TAIYO ELECTRIC IND.CO.LTD | AMK107AC6106MA-T |  | PWA BOM |  |
| OOOOOOOOOOOOOOOOOOOOOOOOOOOOOOOOOOOOOOOOOOOOOOOOOOOOOOOOOOOOOOOOOOOOOOOOOOOOOOOOOOOOOOOOOO | OOOOOOOOOOOOOOOOOOOOOOOOOOOOOOOOOOOOOOOOOOOOOOOOOOOOOOOOOOOOOOOOOOOOOOOOOOOOOOOOOOOOOOOOOO | OOOOOOOOOOOOOOOOOOOOOOOOOOOOOOOOOOOOOOOOOOOOOOOOOOOOOOOOOOOOOOOOOOOOOOOOOOOOOOOOOOOOOOOOOO | OOOOOOOOOOOOOOOOOOOOOOOOOOOOOOOOOOOOOOOOOOOOOOOOOOOOOOOOOOOOOOOOOOOOOOOOOOOOOOOOOOOOOOOOOO | OOOOOOOOOOOOOOOOOOOOOOOOOOOOOOOOOOOOOOOOOOOOOOOOOOOOOOOOOOOOOOOOOOOOOOOOOOOOOOOOOOOOOOOOOO | OOOOOOOOOOOOOOOOOOOOOOOOOOOOOOOOOOOOOOOOOOOOOOOOOOOOOOOOOOOOOOOOOOOOOOOOOOOOOOOOOOOOOOOOOO | OOOOOOOOOOOOOOOOOOOOOOOOOOOOOOOOOOOOOOOOOOOOOOOOOOOOOOOOOOOOOOOOOOOOOOOOOOOOOOOOOOOOOOOOOO | OOOOOOOOOOOOOOOOOOOOOOOOOOOOOOOOOOOOOOOOOOOOOOOOOOOOOOOOOOOOOOOOOOOOOOOOOOOOOOOOOOOOOOOOOO | OOOOOOOOOOOOOOOOOOOOOOOOOOOOOOOOOOOOOOOOOOOOOOOOOOOOOOOOOOOOOOOOOOOOOOOOOOOOOOOOOOOOOOOOOO | OOOOOOOOOOOOOOOOOOOOOOOOOOOOOOOOOOOOOOOOOOOOOOOOOOOOOOOOOOOOOOOOOOOOOOOOOOOOOOOOOOOOOOOOOO |
| Master Materials Change |  |  |  |  |  |  |  |  |  |
| Item | Foxconn P/N | Orig._Usage | New_Usage | Part Description | Manufacturer Full Name | Manufacturer P/N | RoHS | Location | Sheet |
| 1 | 610107A00-017-G | 714 | 712 | RES,0 Ohm,+/-5%,1/16W,G,SMD0402 | KOA SPEER ELECTRONICS, INC. | RK73Z1ETTP |  | (-)R909,R921 | PWA BOM |
|  | 610107A00-024-G |  |  | RES,0 Ohm,+/-5%,1/16W,G,SMD0402 | PANASONIC INDUSTRIAL CO.,LTD. | ERJ2GE0R00X |  |  | PWA BOM |
|  | 610107A00-029-G |  |  | RES,0 Ohm,+/-5%,1/16W,G,SMD0402 | VISHAY ENTER TECHNO LOGY.INC | CRCW04020000Z0ED |  |  | PWA BOM |
| 2 | 10061913-102HLF | 0 | 2 | CONN,PCIE-8X,V/T,Bla,1mm,30u,G,SMD-98 | FCI CONNECTORS HONGKONG LTD. | 10061913-102HLF |  | (+)PCIE1,PCIE5 | PWA BOM |
| 3 | 10061913-103HLF | 0 | 3 | CONN,PCIE-16X,V/T,Bla,1mm,30u,G,SMD-164 | FCI CONNECTORS HONGKONG LTD. | 10061913-103HLF |  | (+)PCIE2,PCIE3,PCIE4 | PWA BOM |
| 4 | 340316300-G78-G | 2 | 0 | CONN,PCIE-8X,V/T,Bla,1mm,30u,G,SMD-98 | FCI CONNECTORS HONGKONG LTD. | 10061913-102PLF |  | (-)PCIE1,PCIE5 | PWA BOM |
| 5 | 34031U600-G78-G | 3 | 0 | CONN,PCIE-16X,V/T,Bla,1mm,30u,G,SMD-164 | FCI CONNECTORS HONGKONG LTD. | 10061913-103BLF |  | (-)PCIE2,PCIE3,PCIE4 | PWA BOM |
| OOOOOOOOOOOOOOOOOOOOOOOOOOOOOOOOOOOOOOOOOOOOOOOOOOOOOOOOOOOOOOOOOOOOOOOOOOOOOOOOOOOOOOOOOO | OOOOOOOOOOOOOOOOOOOOOOOOOOOOOOOOOOOOOOOOOOOOOOOOOOOOOOOOOOOOOOOOOOOOOOOOOOOOOOOOOOOOOOOOOO | OOOOOOOOOOOOOOOOOOOOOOOOOOOOOOOOOOOOOOOOOOOOOOOOOOOOOOOOOOOOOOOOOOOOOOOOOOOOOOOOOOOOOOOOOO | OOOOOOOOOOOOOOOOOOOOOOOOOOOOOOOOOOOOOOOOOOOOOOOOOOOOOOOOOOOOOOOOOOOOOOOOOOOOOOOOOOOOOOOOOO | OOOOOOOOOOOOOOOOOOOOOOOOOOOOOOOOOOOOOOOOOOOOOOOOOOOOOOOOOOOOOOOOOOOOOOOOOOOOOOOOOOOOOOOOOO | OOOOOOOOOOOOOOOOOOOOOOOOOOOOOOOOOOOOOOOOOOOOOOOOOOOOOOOOOOOOOOOOOOOOOOOOOOOOOOOOOOOOOOOOOO | OOOOOOOOOOOOOOOOOOOOOOOOOOOOOOOOOOOOOOOOOOOOOOOOOOOOOOOOOOOOOOOOOOOOOOOOOOOOOOOOOOOOOOOOOO | OOOOOOOOOOOOOOOOOOOOOOOOOOOOOOOOOOOOOOOOOOOOOOOOOOOOOOOOOOOOOOOOOOOOOOOOOOOOOOOOOOOOOOOOOO | OOOOOOOOOOOOOOOOOOOOOOOOOOOOOOOOOOOOOOOOOOOOOOOOOOOOOOOOOOOOOOOOOOOOOOOOOOOOOOOOOOOOOOOOOO |  |
| TLA Parts Change |  |  |  |  |  |  |  |  |  |
| Item | Foxconn P/N | Qty | Part Description | Manufacturer Full Name | Manufacturer P/N | RoHS | Location | Remark |  |
